(kicad_sch
	(version 20250114)
	(generator "eeschema")
	(generator_version "9.0")
	(paper "A3")
	(title_block
		(title "LPDDR5 Testbed")
		(date "2023-12-19")
		(rev "1.0.0")
	)
	(text "Voltage translators"
		(exclude_from_sim no)
		(at 22.86 22.225 0)
		(effects
			(font
				(size 2.4892 2.4892)
				(thickness 0.4978)
				(bold yes)
			)
			(justify left bottom)
		)
	)
	(junction
		(at 279.4 132.08)
		(diameter 0)
		(color 0 0 0 0)
	)
	(junction
		(at 279.4 146.05)
		(diameter 0)
		(color 0 0 0 0)
	)
	(junction
		(at 279.4 95.25)
		(diameter 0)
		(color 0 0 0 0)
	)
	(junction
		(at 279.4 87.63)
		(diameter 0)
		(color 0 0 0 0)
	)
	(junction
		(at 279.4 173.99)
		(diameter 0)
		(color 0 0 0 0)
	)
	(junction
		(at 279.4 129.54)
		(diameter 0)
		(color 0 0 0 0)
	)
	(junction
		(at 279.4 137.16)
		(diameter 0)
		(color 0 0 0 0)
	)
	(junction
		(at 279.4 134.62)
		(diameter 0)
		(color 0 0 0 0)
	)
	(junction
		(at 279.4 59.69)
		(diameter 0)
		(color 0 0 0 0)
	)
	(junction
		(at 279.4 101.6)
		(diameter 0)
		(color 0 0 0 0)
	)
	(junction
		(at 279.4 48.26)
		(diameter 0)
		(color 0 0 0 0)
	)
	(junction
		(at 279.4 118.11)
		(diameter 0)
		(color 0 0 0 0)
	)
	(junction
		(at 279.4 120.65)
		(diameter 0)
		(color 0 0 0 0)
	)
	(junction
		(at 279.4 109.22)
		(diameter 0)
		(color 0 0 0 0)
	)
	(junction
		(at 279.4 115.57)
		(diameter 0)
		(color 0 0 0 0)
	)
	(junction
		(at 279.4 50.8)
		(diameter 0)
		(color 0 0 0 0)
	)
	(junction
		(at 279.4 53.34)
		(diameter 0)
		(color 0 0 0 0)
	)
	(junction
		(at 279.4 104.14)
		(diameter 0)
		(color 0 0 0 0)
	)
	(junction
		(at 279.4 64.77)
		(diameter 0)
		(color 0 0 0 0)
	)
	(junction
		(at 279.4 123.19)
		(diameter 0)
		(color 0 0 0 0)
	)
	(junction
		(at 279.4 106.68)
		(diameter 0)
		(color 0 0 0 0)
	)
	(junction
		(at 279.4 160.02)
		(diameter 0)
		(color 0 0 0 0)
	)
	(junction
		(at 279.4 176.53)
		(diameter 0)
		(color 0 0 0 0)
	)
	(junction
		(at 279.4 81.28)
		(diameter 0)
		(color 0 0 0 0)
	)
	(junction
		(at 279.4 67.31)
		(diameter 0)
		(color 0 0 0 0)
	)
	(junction
		(at 279.4 78.74)
		(diameter 0)
		(color 0 0 0 0)
	)
	(junction
		(at 279.4 148.59)
		(diameter 0)
		(color 0 0 0 0)
	)
	(junction
		(at 279.4 92.71)
		(diameter 0)
		(color 0 0 0 0)
	)
	(junction
		(at 279.4 62.23)
		(diameter 0)
		(color 0 0 0 0)
	)
	(junction
		(at 279.4 162.56)
		(diameter 0)
		(color 0 0 0 0)
	)
	(junction
		(at 279.4 76.2)
		(diameter 0)
		(color 0 0 0 0)
	)
	(junction
		(at 279.4 90.17)
		(diameter 0)
		(color 0 0 0 0)
	)
	(no_connect
		(at 577.85 162.56)
	)
	(bus_entry
		(at 224.79 172.72)
		(size 1.27 1.27)
		(stroke
			(width 0)
			(type default)
		)
	)
	(bus_entry
		(at 148.59 238.76)
		(size -1.27 1.27)
		(stroke
			(width 0)
			(type default)
		)
	)
	(bus_entry
		(at 148.59 218.44)
		(size -1.27 1.27)
		(stroke
			(width 0)
			(type default)
		)
	)
	(bus_entry
		(at 224.79 116.84)
		(size 1.27 1.27)
		(stroke
			(width 0)
			(type default)
		)
	)
	(bus_entry
		(at 224.79 195.58)
		(size -1.27 1.27)
		(stroke
			(width 0)
			(type default)
		)
	)
	(bus_entry
		(at 148.59 256.54)
		(size -1.27 1.27)
		(stroke
			(width 0)
			(type default)
		)
	)
	(bus_entry
		(at 224.79 240.03)
		(size -1.27 1.27)
		(stroke
			(width 0)
			(type default)
		)
	)
	(bus_entry
		(at 148.59 199.39)
		(size -1.27 1.27)
		(stroke
			(width 0)
			(type default)
		)
	)
	(bus_entry
		(at 224.79 135.89)
		(size 1.27 1.27)
		(stroke
			(width 0)
			(type default)
		)
	)
	(bus_entry
		(at 147.32 74.93)
		(size 1.27 1.27)
		(stroke
			(width 0)
			(type default)
		)
	)
	(bus_entry
		(at 147.32 88.9)
		(size 1.27 1.27)
		(stroke
			(width 0)
			(type default)
		)
	)
	(bus_entry
		(at 224.79 231.14)
		(size -1.27 1.27)
		(stroke
			(width 0)
			(type default)
		)
	)
	(bus_entry
		(at 224.79 91.44)
		(size 1.27 1.27)
		(stroke
			(width 0)
			(type default)
		)
	)
	(bus_entry
		(at 224.79 58.42)
		(size -1.27 1.27)
		(stroke
			(width 0)
			(type default)
		)
	)
	(bus_entry
		(at 148.59 261.62)
		(size -1.27 1.27)
		(stroke
			(width 0)
			(type default)
		)
	)
	(bus_entry
		(at 147.32 91.44)
		(size 1.27 1.27)
		(stroke
			(width 0)
			(type default)
		)
	)
	(bus_entry
		(at 147.32 86.36)
		(size 1.27 1.27)
		(stroke
			(width 0)
			(type default)
		)
	)
	(bus_entry
		(at 148.59 224.79)
		(size -1.27 1.27)
		(stroke
			(width 0)
			(type default)
		)
	)
	(bus_entry
		(at 224.79 144.78)
		(size 1.27 1.27)
		(stroke
			(width 0)
			(type default)
		)
	)
	(bus_entry
		(at 224.79 66.04)
		(size 1.27 1.27)
		(stroke
			(width 0)
			(type default)
		)
	)
	(bus_entry
		(at 148.59 241.3)
		(size -1.27 1.27)
		(stroke
			(width 0)
			(type default)
		)
	)
	(bus_entry
		(at 147.32 121.92)
		(size 1.27 1.27)
		(stroke
			(width 0)
			(type default)
		)
	)
	(bus_entry
		(at 224.79 252.73)
		(size -1.27 1.27)
		(stroke
			(width 0)
			(type default)
		)
	)
	(bus_entry
		(at 224.79 49.53)
		(size 1.27 1.27)
		(stroke
			(width 0)
			(type default)
		)
	)
	(bus_entry
		(at 224.79 86.36)
		(size 1.27 1.27)
		(stroke
			(width 0)
			(type default)
		)
	)
	(bus_entry
		(at 224.79 105.41)
		(size 1.27 1.27)
		(stroke
			(width 0)
			(type default)
		)
	)
	(bus_entry
		(at 148.59 204.47)
		(size -1.27 1.27)
		(stroke
			(width 0)
			(type default)
		)
	)
	(bus_entry
		(at 224.79 237.49)
		(size -1.27 1.27)
		(stroke
			(width 0)
			(type default)
		)
	)
	(bus_entry
		(at 224.79 114.3)
		(size -1.27 1.27)
		(stroke
			(width 0)
			(type default)
		)
	)
	(bus_entry
		(at 224.79 128.27)
		(size -1.27 1.27)
		(stroke
			(width 0)
			(type default)
		)
	)
	(bus_entry
		(at 147.32 58.42)
		(size 1.27 1.27)
		(stroke
			(width 0)
			(type default)
		)
	)
	(bus_entry
		(at 224.79 172.72)
		(size -1.27 1.27)
		(stroke
			(width 0)
			(type default)
		)
	)
	(bus_entry
		(at 224.79 91.44)
		(size -1.27 1.27)
		(stroke
			(width 0)
			(type default)
		)
	)
	(bus_entry
		(at 147.32 52.07)
		(size 1.27 1.27)
		(stroke
			(width 0)
			(type default)
		)
	)
	(bus_entry
		(at 224.79 116.84)
		(size -1.27 1.27)
		(stroke
			(width 0)
			(type default)
		)
	)
	(bus_entry
		(at 224.79 86.36)
		(size -1.27 1.27)
		(stroke
			(width 0)
			(type default)
		)
	)
	(bus_entry
		(at 224.79 100.33)
		(size -1.27 1.27)
		(stroke
			(width 0)
			(type default)
		)
	)
	(bus_entry
		(at 147.32 46.99)
		(size 1.27 1.27)
		(stroke
			(width 0)
			(type default)
		)
	)
	(bus_entry
		(at 224.79 242.57)
		(size -1.27 1.27)
		(stroke
			(width 0)
			(type default)
		)
	)
	(bus_entry
		(at 224.79 121.92)
		(size 1.27 1.27)
		(stroke
			(width 0)
			(type default)
		)
	)
	(bus_entry
		(at 147.32 44.45)
		(size 1.27 1.27)
		(stroke
			(width 0)
			(type default)
		)
	)
	(bus_entry
		(at 224.79 260.35)
		(size -1.27 1.27)
		(stroke
			(width 0)
			(type default)
		)
	)
	(bus_entry
		(at 224.79 147.32)
		(size -1.27 1.27)
		(stroke
			(width 0)
			(type default)
		)
	)
	(bus_entry
		(at 224.79 105.41)
		(size -1.27 1.27)
		(stroke
			(width 0)
			(type default)
		)
	)
	(bus_entry
		(at 147.32 144.78)
		(size 1.27 1.27)
		(stroke
			(width 0)
			(type default)
		)
	)
	(bus_entry
		(at 224.79 66.04)
		(size -1.27 1.27)
		(stroke
			(width 0)
			(type default)
		)
	)
	(bus_entry
		(at 147.32 80.01)
		(size 1.27 1.27)
		(stroke
			(width 0)
			(type default)
		)
	)
	(bus_entry
		(at 224.79 133.35)
		(size -1.27 1.27)
		(stroke
			(width 0)
			(type default)
		)
	)
	(bus_entry
		(at 224.79 161.29)
		(size 1.27 1.27)
		(stroke
			(width 0)
			(type default)
		)
	)
	(bus_entry
		(at 224.79 74.93)
		(size 1.27 1.27)
		(stroke
			(width 0)
			(type default)
		)
	)
	(bus_entry
		(at 224.79 63.5)
		(size -1.27 1.27)
		(stroke
			(width 0)
			(type default)
		)
	)
	(bus_entry
		(at 147.32 107.95)
		(size 1.27 1.27)
		(stroke
			(width 0)
			(type default)
		)
	)
	(bus_entry
		(at 148.59 194.31)
		(size -1.27 1.27)
		(stroke
			(width 0)
			(type default)
		)
	)
	(bus_entry
		(at 148.59 246.38)
		(size -1.27 1.27)
		(stroke
			(width 0)
			(type default)
		)
	)
	(bus_entry
		(at 224.79 46.99)
		(size 1.27 1.27)
		(stroke
			(width 0)
			(type default)
		)
	)
	(bus_entry
		(at 224.79 52.07)
		(size -1.27 1.27)
		(stroke
			(width 0)
			(type default)
		)
	)
	(bus_entry
		(at 148.59 238.76)
		(size -1.27 1.27)
		(stroke
			(width 0)
			(type default)
		)
	)
	(bus_entry
		(at 224.79 60.96)
		(size -1.27 1.27)
		(stroke
			(width 0)
			(type default)
		)
	)
	(bus_entry
		(at 147.32 158.75)
		(size 1.27 1.27)
		(stroke
			(width 0)
			(type default)
		)
	)
	(bus_entry
		(at 147.32 105.41)
		(size 1.27 1.27)
		(stroke
			(width 0)
			(type default)
		)
	)
	(bus_entry
		(at 224.79 212.09)
		(size -1.27 1.27)
		(stroke
			(width 0)
			(type default)
		)
	)
	(bus_entry
		(at 148.59 254)
		(size -1.27 1.27)
		(stroke
			(width 0)
			(type default)
		)
	)
	(bus_entry
		(at 224.79 60.96)
		(size 1.27 1.27)
		(stroke
			(width 0)
			(type default)
		)
	)
	(bus_entry
		(at 224.79 93.98)
		(size -1.27 1.27)
		(stroke
			(width 0)
			(type default)
		)
	)
	(bus_entry
		(at 224.79 245.11)
		(size -1.27 1.27)
		(stroke
			(width 0)
			(type default)
		)
	)
	(bus_entry
		(at 148.59 213.36)
		(size -1.27 1.27)
		(stroke
			(width 0)
			(type default)
		)
	)
	(bus_entry
		(at 147.32 93.98)
		(size 1.27 1.27)
		(stroke
			(width 0)
			(type default)
		)
	)
	(bus_entry
		(at 224.79 214.63)
		(size -1.27 1.27)
		(stroke
			(width 0)
			(type default)
		)
	)
	(bus_entry
		(at 224.79 80.01)
		(size 1.27 1.27)
		(stroke
			(width 0)
			(type default)
		)
	)
	(bus_entry
		(at 147.32 135.89)
		(size 1.27 1.27)
		(stroke
			(width 0)
			(type default)
		)
	)
	(bus_entry
		(at 148.59 201.93)
		(size -1.27 1.27)
		(stroke
			(width 0)
			(type default)
		)
	)
	(bus_entry
		(at 147.32 77.47)
		(size 1.27 1.27)
		(stroke
			(width 0)
			(type default)
		)
	)
	(bus_entry
		(at 148.59 243.84)
		(size -1.27 1.27)
		(stroke
			(width 0)
			(type default)
		)
	)
	(bus_entry
		(at 224.79 190.5)
		(size -1.27 1.27)
		(stroke
			(width 0)
			(type default)
		)
	)
	(bus_entry
		(at 224.79 133.35)
		(size 1.27 1.27)
		(stroke
			(width 0)
			(type default)
		)
	)
	(bus_entry
		(at 224.79 193.04)
		(size -1.27 1.27)
		(stroke
			(width 0)
			(type default)
		)
	)
	(bus_entry
		(at 224.79 223.52)
		(size -1.27 1.27)
		(stroke
			(width 0)
			(type default)
		)
	)
	(bus_entry
		(at 147.32 116.84)
		(size 1.27 1.27)
		(stroke
			(width 0)
			(type default)
		)
	)
	(bus_entry
		(at 147.32 175.26)
		(size 1.27 1.27)
		(stroke
			(width 0)
			(type default)
		)
	)
	(bus_entry
		(at 147.32 100.33)
		(size 1.27 1.27)
		(stroke
			(width 0)
			(type default)
		)
	)
	(bus_entry
		(at 224.79 255.27)
		(size -1.27 1.27)
		(stroke
			(width 0)
			(type default)
		)
	)
	(bus_entry
		(at 224.79 107.95)
		(size -1.27 1.27)
		(stroke
			(width 0)
			(type default)
		)
	)
	(bus_entry
		(at 224.79 63.5)
		(size 1.27 1.27)
		(stroke
			(width 0)
			(type default)
		)
	)
	(bus_entry
		(at 147.32 130.81)
		(size 1.27 1.27)
		(stroke
			(width 0)
			(type default)
		)
	)
	(bus_entry
		(at 224.79 44.45)
		(size 1.27 1.27)
		(stroke
			(width 0)
			(type default)
		)
	)
	(bus_entry
		(at 147.32 133.35)
		(size 1.27 1.27)
		(stroke
			(width 0)
			(type default)
		)
	)
	(bus_entry
		(at 147.32 66.04)
		(size 1.27 1.27)
		(stroke
			(width 0)
			(type default)
		)
	)
	(bus_entry
		(at 224.79 128.27)
		(size 1.27 1.27)
		(stroke
			(width 0)
			(type default)
		)
	)
	(bus_entry
		(at 224.79 100.33)
		(size 1.27 1.27)
		(stroke
			(width 0)
			(type default)
		)
	)
	(bus_entry
		(at 224.79 228.6)
		(size -1.27 1.27)
		(stroke
			(width 0)
			(type default)
		)
	)
	(bus_entry
		(at 147.32 147.32)
		(size 1.27 1.27)
		(stroke
			(width 0)
			(type default)
		)
	)
	(bus_entry
		(at 224.79 77.47)
		(size -1.27 1.27)
		(stroke
			(width 0)
			(type default)
		)
	)
	(bus_entry
		(at 224.79 80.01)
		(size -1.27 1.27)
		(stroke
			(width 0)
			(type default)
		)
	)
	(bus_entry
		(at 224.79 161.29)
		(size -1.27 1.27)
		(stroke
			(width 0)
			(type default)
		)
	)
	(bus_entry
		(at 224.79 88.9)
		(size 1.27 1.27)
		(stroke
			(width 0)
			(type default)
		)
	)
	(bus_entry
		(at 224.79 135.89)
		(size -1.27 1.27)
		(stroke
			(width 0)
			(type default)
		)
	)
	(bus_entry
		(at 148.59 196.85)
		(size -1.27 1.27)
		(stroke
			(width 0)
			(type default)
		)
	)
	(bus_entry
		(at 148.59 229.87)
		(size -1.27 1.27)
		(stroke
			(width 0)
			(type default)
		)
	)
	(bus_entry
		(at 147.32 161.29)
		(size 1.27 1.27)
		(stroke
			(width 0)
			(type default)
		)
	)
	(bus_entry
		(at 224.79 44.45)
		(size -1.27 1.27)
		(stroke
			(width 0)
			(type default)
		)
	)
	(bus_entry
		(at 224.79 144.78)
		(size -1.27 1.27)
		(stroke
			(width 0)
			(type default)
		)
	)
	(bus_entry
		(at 224.79 93.98)
		(size 1.27 1.27)
		(stroke
			(width 0)
			(type default)
		)
	)
	(bus_entry
		(at 224.79 158.75)
		(size -1.27 1.27)
		(stroke
			(width 0)
			(type default)
		)
	)
	(bus_entry
		(at 224.79 147.32)
		(size 1.27 1.27)
		(stroke
			(width 0)
			(type default)
		)
	)
	(bus_entry
		(at 224.79 200.66)
		(size -1.27 1.27)
		(stroke
			(width 0)
			(type default)
		)
	)
	(bus_entry
		(at 224.79 46.99)
		(size -1.27 1.27)
		(stroke
			(width 0)
			(type default)
		)
	)
	(bus_entry
		(at 147.32 172.72)
		(size 1.27 1.27)
		(stroke
			(width 0)
			(type default)
		)
	)
	(bus_entry
		(at 147.32 119.38)
		(size 1.27 1.27)
		(stroke
			(width 0)
			(type default)
		)
	)
	(bus_entry
		(at 148.59 259.08)
		(size -1.27 1.27)
		(stroke
			(width 0)
			(type default)
		)
	)
	(bus_entry
		(at 224.79 130.81)
		(size -1.27 1.27)
		(stroke
			(width 0)
			(type default)
		)
	)
	(bus_entry
		(at 224.79 74.93)
		(size -1.27 1.27)
		(stroke
			(width 0)
			(type default)
		)
	)
	(bus_entry
		(at 224.79 114.3)
		(size 1.27 1.27)
		(stroke
			(width 0)
			(type default)
		)
	)
	(bus_entry
		(at 147.32 128.27)
		(size 1.27 1.27)
		(stroke
			(width 0)
			(type default)
		)
	)
	(bus_entry
		(at 224.79 119.38)
		(size 1.27 1.27)
		(stroke
			(width 0)
			(type default)
		)
	)
	(bus_entry
		(at 148.59 224.79)
		(size -1.27 1.27)
		(stroke
			(width 0)
			(type default)
		)
	)
	(bus_entry
		(at 224.79 52.07)
		(size 1.27 1.27)
		(stroke
			(width 0)
			(type default)
		)
	)
	(bus_entry
		(at 224.79 203.2)
		(size -1.27 1.27)
		(stroke
			(width 0)
			(type default)
		)
	)
	(bus_entry
		(at 148.59 210.82)
		(size -1.27 1.27)
		(stroke
			(width 0)
			(type default)
		)
	)
	(bus_entry
		(at 224.79 257.81)
		(size -1.27 1.27)
		(stroke
			(width 0)
			(type default)
		)
	)
	(bus_entry
		(at 224.79 226.06)
		(size -1.27 1.27)
		(stroke
			(width 0)
			(type default)
		)
	)
	(bus_entry
		(at 147.32 102.87)
		(size 1.27 1.27)
		(stroke
			(width 0)
			(type default)
		)
	)
	(bus_entry
		(at 224.79 217.17)
		(size -1.27 1.27)
		(stroke
			(width 0)
			(type default)
		)
	)
	(bus_entry
		(at 147.32 60.96)
		(size 1.27 1.27)
		(stroke
			(width 0)
			(type default)
		)
	)
	(bus_entry
		(at 147.32 49.53)
		(size 1.27 1.27)
		(stroke
			(width 0)
			(type default)
		)
	)
	(bus_entry
		(at 224.79 130.81)
		(size 1.27 1.27)
		(stroke
			(width 0)
			(type default)
		)
	)
	(bus_entry
		(at 147.32 63.5)
		(size 1.27 1.27)
		(stroke
			(width 0)
			(type default)
		)
	)
	(bus_entry
		(at 224.79 175.26)
		(size 1.27 1.27)
		(stroke
			(width 0)
			(type default)
		)
	)
	(bus_entry
		(at 148.59 232.41)
		(size -1.27 1.27)
		(stroke
			(width 0)
			(type default)
		)
	)
	(bus_entry
		(at 224.79 49.53)
		(size -1.27 1.27)
		(stroke
			(width 0)
			(type default)
		)
	)
	(bus_entry
		(at 148.59 191.77)
		(size -1.27 1.27)
		(stroke
			(width 0)
			(type default)
		)
	)
	(bus_entry
		(at 224.79 102.87)
		(size -1.27 1.27)
		(stroke
			(width 0)
			(type default)
		)
	)
	(bus_entry
		(at 224.79 119.38)
		(size -1.27 1.27)
		(stroke
			(width 0)
			(type default)
		)
	)
	(bus_entry
		(at 147.32 114.3)
		(size 1.27 1.27)
		(stroke
			(width 0)
			(type default)
		)
	)
	(bus_entry
		(at 224.79 175.26)
		(size -1.27 1.27)
		(stroke
			(width 0)
			(type default)
		)
	)
	(bus_entry
		(at 224.79 88.9)
		(size -1.27 1.27)
		(stroke
			(width 0)
			(type default)
		)
	)
	(bus_entry
		(at 224.79 209.55)
		(size -1.27 1.27)
		(stroke
			(width 0)
			(type default)
		)
	)
	(bus_entry
		(at 224.79 198.12)
		(size -1.27 1.27)
		(stroke
			(width 0)
			(type default)
		)
	)
	(bus_entry
		(at 224.79 77.47)
		(size 1.27 1.27)
		(stroke
			(width 0)
			(type default)
		)
	)
	(bus_entry
		(at 148.59 215.9)
		(size -1.27 1.27)
		(stroke
			(width 0)
			(type default)
		)
	)
	(bus_entry
		(at 224.79 58.42)
		(size 1.27 1.27)
		(stroke
			(width 0)
			(type default)
		)
	)
	(bus_entry
		(at 224.79 102.87)
		(size 1.27 1.27)
		(stroke
			(width 0)
			(type default)
		)
	)
	(bus_entry
		(at 224.79 158.75)
		(size 1.27 1.27)
		(stroke
			(width 0)
			(type default)
		)
	)
	(bus_entry
		(at 148.59 227.33)
		(size -1.27 1.27)
		(stroke
			(width 0)
			(type default)
		)
	)
	(bus_entry
		(at 224.79 107.95)
		(size 1.27 1.27)
		(stroke
			(width 0)
			(type default)
		)
	)
	(bus_entry
		(at 224.79 121.92)
		(size -1.27 1.27)
		(stroke
			(width 0)
			(type default)
		)
	)
	(bus
		(pts
			(xy 224.79 212.09) (xy 224.79 214.63)
		)
		(stroke
			(width 0)
			(type default)
		)
	)
	(wire
		(pts
			(xy 189.23 120.65) (xy 223.52 120.65)
		)
		(stroke
			(width 0)
			(type default)
		)
	)
	(wire
		(pts
			(xy 270.51 129.54) (xy 279.4 129.54)
		)
		(stroke
			(width 0)
			(type default)
		)
	)
	(bus
		(pts
			(xy 147.32 114.3) (xy 147.32 116.84)
		)
		(stroke
			(width 0)
			(type default)
		)
	)
	(wire
		(pts
			(xy 279.4 148.59) (xy 279.4 160.02)
		)
		(stroke
			(width 0)
			(type default)
		)
	)
	(wire
		(pts
			(xy 148.59 224.79) (xy 223.52 224.79)
		)
		(stroke
			(width 0)
			(type default)
		)
	)
	(wire
		(pts
			(xy 148.59 106.68) (xy 179.07 106.68)
		)
		(stroke
			(width 0)
			(type default)
		)
	)
	(wire
		(pts
			(xy 279.4 87.63) (xy 279.4 90.17)
		)
		(stroke
			(width 0)
			(type default)
		)
	)
	(wire
		(pts
			(xy 226.06 137.16) (xy 260.35 137.16)
		)
		(stroke
			(width 0)
			(type default)
		)
	)
	(wire
		(pts
			(xy 148.59 173.99) (xy 181.61 173.99)
		)
		(stroke
			(width 0)
			(type default)
		)
	)
	(bus
		(pts
			(xy 147.32 245.11) (xy 147.32 247.65)
		)
		(stroke
			(width 0)
			(type default)
		)
	)
	(wire
		(pts
			(xy 279.4 62.23) (xy 279.4 64.77)
		)
		(stroke
			(width 0)
			(type default)
		)
	)
	(wire
		(pts
			(xy 226.06 148.59) (xy 262.89 148.59)
		)
		(stroke
			(width 0)
			(type default)
		)
	)
	(bus
		(pts
			(xy 147.32 80.01) (xy 147.32 86.36)
		)
		(stroke
			(width 0)
			(type default)
		)
	)
	(bus
		(pts
			(xy 147.32 198.12) (xy 147.32 200.66)
		)
		(stroke
			(width 0)
			(type default)
		)
	)
	(wire
		(pts
			(xy 148.59 67.31) (xy 179.07 67.31)
		)
		(stroke
			(width 0)
			(type default)
		)
	)
	(wire
		(pts
			(xy 267.97 162.56) (xy 279.4 162.56)
		)
		(stroke
			(width 0)
			(type default)
		)
	)
	(bus
		(pts
			(xy 147.32 102.87) (xy 147.32 105.41)
		)
		(stroke
			(width 0)
			(type default)
		)
	)
	(wire
		(pts
			(xy 270.51 95.25) (xy 279.4 95.25)
		)
		(stroke
			(width 0)
			(type default)
		)
	)
	(bus
		(pts
			(xy 147.32 219.71) (xy 147.32 226.06)
		)
		(stroke
			(width 0)
			(type default)
		)
	)
	(bus
		(pts
			(xy 147.32 121.92) (xy 147.32 128.27)
		)
		(stroke
			(width 0)
			(type default)
		)
	)
	(bus
		(pts
			(xy 224.79 116.84) (xy 224.79 119.38)
		)
		(stroke
			(width 0)
			(type default)
		)
	)
	(wire
		(pts
			(xy 226.06 134.62) (xy 260.35 134.62)
		)
		(stroke
			(width 0)
			(type default)
		)
	)
	(bus
		(pts
			(xy 147.32 88.9) (xy 147.32 91.44)
		)
		(stroke
			(width 0)
			(type default)
		)
	)
	(wire
		(pts
			(xy 148.59 64.77) (xy 179.07 64.77)
		)
		(stroke
			(width 0)
			(type default)
		)
	)
	(wire
		(pts
			(xy 148.59 92.71) (xy 179.07 92.71)
		)
		(stroke
			(width 0)
			(type default)
		)
	)
	(wire
		(pts
			(xy 279.4 48.26) (xy 279.4 50.8)
		)
		(stroke
			(width 0)
			(type default)
		)
	)
	(wire
		(pts
			(xy 148.59 213.36) (xy 223.52 213.36)
		)
		(stroke
			(width 0)
			(type default)
		)
	)
	(wire
		(pts
			(xy 186.69 76.2) (xy 223.52 76.2)
		)
		(stroke
			(width 0)
			(type default)
		)
	)
	(wire
		(pts
			(xy 148.59 50.8) (xy 179.07 50.8)
		)
		(stroke
			(width 0)
			(type default)
		)
	)
	(bus
		(pts
			(xy 147.32 46.99) (xy 147.32 49.53)
		)
		(stroke
			(width 0)
			(type default)
		)
	)
	(wire
		(pts
			(xy 189.23 104.14) (xy 223.52 104.14)
		)
		(stroke
			(width 0)
			(type default)
		)
	)
	(bus
		(pts
			(xy 224.79 217.17) (xy 224.79 223.52)
		)
		(stroke
			(width 0)
			(type default)
		)
	)
	(wire
		(pts
			(xy 226.06 92.71) (xy 260.35 92.71)
		)
		(stroke
			(width 0)
			(type default)
		)
	)
	(wire
		(pts
			(xy 267.97 160.02) (xy 279.4 160.02)
		)
		(stroke
			(width 0)
			(type default)
		)
	)
	(bus
		(pts
			(xy 224.79 100.33) (xy 224.79 102.87)
		)
		(stroke
			(width 0)
			(type default)
		)
	)
	(wire
		(pts
			(xy 279.4 132.08) (xy 279.4 134.62)
		)
		(stroke
			(width 0)
			(type default)
		)
	)
	(wire
		(pts
			(xy 226.06 59.69) (xy 260.35 59.69)
		)
		(stroke
			(width 0)
			(type default)
		)
	)
	(wire
		(pts
			(xy 267.97 148.59) (xy 279.4 148.59)
		)
		(stroke
			(width 0)
			(type default)
		)
	)
	(wire
		(pts
			(xy 226.06 48.26) (xy 260.35 48.26)
		)
		(stroke
			(width 0)
			(type default)
		)
	)
	(bus
		(pts
			(xy 147.32 77.47) (xy 147.32 80.01)
		)
		(stroke
			(width 0)
			(type default)
		)
	)
	(wire
		(pts
			(xy 148.59 194.31) (xy 223.52 194.31)
		)
		(stroke
			(width 0)
			(type default)
		)
	)
	(wire
		(pts
			(xy 270.51 59.69) (xy 279.4 59.69)
		)
		(stroke
			(width 0)
			(type default)
		)
	)
	(wire
		(pts
			(xy 148.59 118.11) (xy 179.07 118.11)
		)
		(stroke
			(width 0)
			(type default)
		)
	)
	(bus
		(pts
			(xy 147.32 203.2) (xy 147.32 205.74)
		)
		(stroke
			(width 0)
			(type default)
		)
	)
	(wire
		(pts
			(xy 270.51 104.14) (xy 279.4 104.14)
		)
		(stroke
			(width 0)
			(type default)
		)
	)
	(bus
		(pts
			(xy 224.79 226.06) (xy 224.79 228.6)
		)
		(stroke
			(width 0)
			(type default)
		)
	)
	(wire
		(pts
			(xy 148.59 160.02) (xy 181.61 160.02)
		)
		(stroke
			(width 0)
			(type default)
		)
	)
	(wire
		(pts
			(xy 226.06 95.25) (xy 260.35 95.25)
		)
		(stroke
			(width 0)
			(type default)
		)
	)
	(wire
		(pts
			(xy 270.51 115.57) (xy 279.4 115.57)
		)
		(stroke
			(width 0)
			(type default)
		)
	)
	(bus
		(pts
			(xy 146.05 27.94) (xy 127 27.94)
		)
		(stroke
			(width 0)
			(type default)
		)
	)
	(wire
		(pts
			(xy 148.59 191.77) (xy 223.52 191.77)
		)
		(stroke
			(width 0)
			(type default)
		)
	)
	(wire
		(pts
			(xy 148.59 204.47) (xy 223.52 204.47)
		)
		(stroke
			(width 0)
			(type default)
		)
	)
	(wire
		(pts
			(xy 279.4 162.56) (xy 279.4 173.99)
		)
		(stroke
			(width 0)
			(type default)
		)
	)
	(bus
		(pts
			(xy 226.06 186.69) (xy 327.66 186.69)
		)
		(stroke
			(width 0)
			(type default)
		)
	)
	(wire
		(pts
			(xy 279.4 109.22) (xy 279.4 115.57)
		)
		(stroke
			(width 0)
			(type default)
		)
	)
	(bus
		(pts
			(xy 147.32 44.45) (xy 147.32 46.99)
		)
		(stroke
			(width 0)
			(type default)
		)
	)
	(wire
		(pts
			(xy 148.59 76.2) (xy 181.61 76.2)
		)
		(stroke
			(width 0)
			(type default)
		)
	)
	(wire
		(pts
			(xy 226.06 78.74) (xy 262.89 78.74)
		)
		(stroke
			(width 0)
			(type default)
		)
	)
	(wire
		(pts
			(xy 148.59 243.84) (xy 223.52 243.84)
		)
		(stroke
			(width 0)
			(type default)
		)
	)
	(wire
		(pts
			(xy 148.59 62.23) (xy 179.07 62.23)
		)
		(stroke
			(width 0)
			(type default)
		)
	)
	(bus
		(pts
			(xy 224.79 187.96) (xy 224.79 190.5)
		)
		(stroke
			(width 0)
			(type default)
		)
	)
	(wire
		(pts
			(xy 148.59 201.93) (xy 223.52 201.93)
		)
		(stroke
			(width 0)
			(type default)
		)
	)
	(wire
		(pts
			(xy 186.69 160.02) (xy 223.52 160.02)
		)
		(stroke
			(width 0)
			(type default)
		)
	)
	(wire
		(pts
			(xy 189.23 87.63) (xy 223.52 87.63)
		)
		(stroke
			(width 0)
			(type default)
		)
	)
	(wire
		(pts
			(xy 148.59 134.62) (xy 179.07 134.62)
		)
		(stroke
			(width 0)
			(type default)
		)
	)
	(wire
		(pts
			(xy 189.23 64.77) (xy 223.52 64.77)
		)
		(stroke
			(width 0)
			(type default)
		)
	)
	(wire
		(pts
			(xy 186.69 81.28) (xy 223.52 81.28)
		)
		(stroke
			(width 0)
			(type default)
		)
	)
	(wire
		(pts
			(xy 270.51 45.72) (xy 279.4 45.72)
		)
		(stroke
			(width 0)
			(type default)
		)
	)
	(wire
		(pts
			(xy 148.59 162.56) (xy 181.61 162.56)
		)
		(stroke
			(width 0)
			(type default)
		)
	)
	(wire
		(pts
			(xy 270.51 90.17) (xy 279.4 90.17)
		)
		(stroke
			(width 0)
			(type default)
		)
	)
	(wire
		(pts
			(xy 189.23 95.25) (xy 223.52 95.25)
		)
		(stroke
			(width 0)
			(type default)
		)
	)
	(bus
		(pts
			(xy 224.79 228.6) (xy 224.79 231.14)
		)
		(stroke
			(width 0)
			(type default)
		)
	)
	(bus
		(pts
			(xy 224.79 88.9) (xy 224.79 91.44)
		)
		(stroke
			(width 0)
			(type default)
		)
	)
	(wire
		(pts
			(xy 279.4 81.28) (xy 279.4 87.63)
		)
		(stroke
			(width 0)
			(type default)
		)
	)
	(wire
		(pts
			(xy 279.4 173.99) (xy 279.4 176.53)
		)
		(stroke
			(width 0)
			(type default)
		)
	)
	(wire
		(pts
			(xy 148.59 241.3) (xy 223.52 241.3)
		)
		(stroke
			(width 0)
			(type default)
		)
	)
	(wire
		(pts
			(xy 270.51 62.23) (xy 279.4 62.23)
		)
		(stroke
			(width 0)
			(type default)
		)
	)
	(wire
		(pts
			(xy 270.51 132.08) (xy 279.4 132.08)
		)
		(stroke
			(width 0)
			(type default)
		)
	)
	(bus
		(pts
			(xy 224.79 91.44) (xy 224.79 93.98)
		)
		(stroke
			(width 0)
			(type default)
		)
	)
	(wire
		(pts
			(xy 279.4 50.8) (xy 279.4 53.34)
		)
		(stroke
			(width 0)
			(type default)
		)
	)
	(wire
		(pts
			(xy 189.23 118.11) (xy 223.52 118.11)
		)
		(stroke
			(width 0)
			(type default)
		)
	)
	(wire
		(pts
			(xy 186.69 162.56) (xy 223.52 162.56)
		)
		(stroke
			(width 0)
			(type default)
		)
	)
	(wire
		(pts
			(xy 186.69 148.59) (xy 223.52 148.59)
		)
		(stroke
			(width 0)
			(type default)
		)
	)
	(wire
		(pts
			(xy 189.23 45.72) (xy 223.52 45.72)
		)
		(stroke
			(width 0)
			(type default)
		)
	)
	(bus
		(pts
			(xy 147.32 52.07) (xy 147.32 58.42)
		)
		(stroke
			(width 0)
			(type default)
		)
	)
	(wire
		(pts
			(xy 279.4 64.77) (xy 279.4 67.31)
		)
		(stroke
			(width 0)
			(type default)
		)
	)
	(wire
		(pts
			(xy 226.06 62.23) (xy 260.35 62.23)
		)
		(stroke
			(width 0)
			(type default)
		)
	)
	(wire
		(pts
			(xy 226.06 118.11) (xy 260.35 118.11)
		)
		(stroke
			(width 0)
			(type default)
		)
	)
	(wire
		(pts
			(xy 189.23 92.71) (xy 223.52 92.71)
		)
		(stroke
			(width 0)
			(type default)
		)
	)
	(bus
		(pts
			(xy 147.32 260.35) (xy 147.32 262.89)
		)
		(stroke
			(width 0)
			(type default)
		)
	)
	(wire
		(pts
			(xy 148.59 176.53) (xy 181.61 176.53)
		)
		(stroke
			(width 0)
			(type default)
		)
	)
	(bus
		(pts
			(xy 224.79 158.75) (xy 224.79 161.29)
		)
		(stroke
			(width 0)
			(type default)
		)
	)
	(wire
		(pts
			(xy 270.51 120.65) (xy 279.4 120.65)
		)
		(stroke
			(width 0)
			(type default)
		)
	)
	(wire
		(pts
			(xy 148.59 238.76) (xy 223.52 238.76)
		)
		(stroke
			(width 0)
			(type default)
		)
	)
	(bus
		(pts
			(xy 224.79 240.03) (xy 224.79 242.57)
		)
		(stroke
			(width 0)
			(type default)
		)
	)
	(wire
		(pts
			(xy 279.4 134.62) (xy 279.4 137.16)
		)
		(stroke
			(width 0)
			(type default)
		)
	)
	(wire
		(pts
			(xy 189.23 101.6) (xy 223.52 101.6)
		)
		(stroke
			(width 0)
			(type default)
		)
	)
	(bus
		(pts
			(xy 224.79 128.27) (xy 224.79 130.81)
		)
		(stroke
			(width 0)
			(type default)
		)
	)
	(wire
		(pts
			(xy 279.4 118.11) (xy 279.4 120.65)
		)
		(stroke
			(width 0)
			(type default)
		)
	)
	(bus
		(pts
			(xy 224.79 172.72) (xy 224.79 175.26)
		)
		(stroke
			(width 0)
			(type default)
		)
	)
	(bus
		(pts
			(xy 147.32 91.44) (xy 147.32 93.98)
		)
		(stroke
			(width 0)
			(type default)
		)
	)
	(wire
		(pts
			(xy 279.4 95.25) (xy 279.4 101.6)
		)
		(stroke
			(width 0)
			(type default)
		)
	)
	(wire
		(pts
			(xy 226.06 120.65) (xy 260.35 120.65)
		)
		(stroke
			(width 0)
			(type default)
		)
	)
	(wire
		(pts
			(xy 226.06 45.72) (xy 260.35 45.72)
		)
		(stroke
			(width 0)
			(type default)
		)
	)
	(bus
		(pts
			(xy 147.32 262.89) (xy 147.32 266.7)
		)
		(stroke
			(width 0)
			(type default)
		)
	)
	(wire
		(pts
			(xy 270.51 64.77) (xy 279.4 64.77)
		)
		(stroke
			(width 0)
			(type default)
		)
	)
	(wire
		(pts
			(xy 270.51 118.11) (xy 279.4 118.11)
		)
		(stroke
			(width 0)
			(type default)
		)
	)
	(bus
		(pts
			(xy 147.32 214.63) (xy 147.32 217.17)
		)
		(stroke
			(width 0)
			(type default)
		)
	)
	(wire
		(pts
			(xy 270.51 134.62) (xy 279.4 134.62)
		)
		(stroke
			(width 0)
			(type default)
		)
	)
	(wire
		(pts
			(xy 148.59 227.33) (xy 223.52 227.33)
		)
		(stroke
			(width 0)
			(type default)
		)
	)
	(wire
		(pts
			(xy 148.59 53.34) (xy 179.07 53.34)
		)
		(stroke
			(width 0)
			(type default)
		)
	)
	(bus
		(pts
			(xy 224.79 44.45) (xy 224.79 46.99)
		)
		(stroke
			(width 0)
			(type default)
		)
	)
	(bus
		(pts
			(xy 147.32 74.93) (xy 147.32 77.47)
		)
		(stroke
			(width 0)
			(type default)
		)
	)
	(wire
		(pts
			(xy 148.59 120.65) (xy 179.07 120.65)
		)
		(stroke
			(width 0)
			(type default)
		)
	)
	(bus
		(pts
			(xy 147.32 107.95) (xy 147.32 114.3)
		)
		(stroke
			(width 0)
			(type default)
		)
	)
	(wire
		(pts
			(xy 226.06 132.08) (xy 260.35 132.08)
		)
		(stroke
			(width 0)
			(type default)
		)
	)
	(bus
		(pts
			(xy 224.79 133.35) (xy 224.79 135.89)
		)
		(stroke
			(width 0)
			(type default)
		)
	)
	(wire
		(pts
			(xy 148.59 132.08) (xy 179.07 132.08)
		)
		(stroke
			(width 0)
			(type default)
		)
	)
	(wire
		(pts
			(xy 148.59 254) (xy 223.52 254)
		)
		(stroke
			(width 0)
			(type default)
		)
	)
	(bus
		(pts
			(xy 224.79 107.95) (xy 224.79 114.3)
		)
		(stroke
			(width 0)
			(type default)
		)
	)
	(wire
		(pts
			(xy 148.59 232.41) (xy 223.52 232.41)
		)
		(stroke
			(width 0)
			(type default)
		)
	)
	(bus
		(pts
			(xy 224.79 21.59) (xy 224.79 44.45)
		)
		(stroke
			(width 0)
			(type default)
		)
	)
	(wire
		(pts
			(xy 279.4 101.6) (xy 279.4 104.14)
		)
		(stroke
			(width 0)
			(type default)
		)
	)
	(bus
		(pts
			(xy 224.79 60.96) (xy 224.79 63.5)
		)
		(stroke
			(width 0)
			(type default)
		)
	)
	(bus
		(pts
			(xy 224.79 209.55) (xy 224.79 212.09)
		)
		(stroke
			(width 0)
			(type default)
		)
	)
	(wire
		(pts
			(xy 226.06 176.53) (xy 262.89 176.53)
		)
		(stroke
			(width 0)
			(type default)
		)
	)
	(bus
		(pts
			(xy 224.79 245.11) (xy 224.79 252.73)
		)
		(stroke
			(width 0)
			(type default)
		)
	)
	(bus
		(pts
			(xy 147.32 119.38) (xy 147.32 121.92)
		)
		(stroke
			(width 0)
			(type default)
		)
	)
	(wire
		(pts
			(xy 186.69 173.99) (xy 223.52 173.99)
		)
		(stroke
			(width 0)
			(type default)
		)
	)
	(bus
		(pts
			(xy 147.32 161.29) (xy 147.32 172.72)
		)
		(stroke
			(width 0)
			(type default)
		)
	)
	(wire
		(pts
			(xy 148.59 104.14) (xy 179.07 104.14)
		)
		(stroke
			(width 0)
			(type default)
		)
	)
	(wire
		(pts
			(xy 226.06 104.14) (xy 260.35 104.14)
		)
		(stroke
			(width 0)
			(type default)
		)
	)
	(wire
		(pts
			(xy 186.69 176.53) (xy 223.52 176.53)
		)
		(stroke
			(width 0)
			(type default)
		)
	)
	(wire
		(pts
			(xy 270.51 67.31) (xy 279.4 67.31)
		)
		(stroke
			(width 0)
			(type default)
		)
	)
	(wire
		(pts
			(xy 267.97 146.05) (xy 279.4 146.05)
		)
		(stroke
			(width 0)
			(type default)
		)
	)
	(wire
		(pts
			(xy 226.06 64.77) (xy 260.35 64.77)
		)
		(stroke
			(width 0)
			(type default)
		)
	)
	(bus
		(pts
			(xy 224.79 52.07) (xy 224.79 58.42)
		)
		(stroke
			(width 0)
			(type default)
		)
	)
	(bus
		(pts
			(xy 147.32 212.09) (xy 147.32 214.63)
		)
		(stroke
			(width 0)
			(type default)
		)
	)
	(bus
		(pts
			(xy 224.79 58.42) (xy 224.79 60.96)
		)
		(stroke
			(width 0)
			(type default)
		)
	)
	(wire
		(pts
			(xy 148.59 45.72) (xy 179.07 45.72)
		)
		(stroke
			(width 0)
			(type default)
		)
	)
	(bus
		(pts
			(xy 147.32 60.96) (xy 147.32 63.5)
		)
		(stroke
			(width 0)
			(type default)
		)
	)
	(wire
		(pts
			(xy 189.23 90.17) (xy 223.52 90.17)
		)
		(stroke
			(width 0)
			(type default)
		)
	)
	(wire
		(pts
			(xy 148.59 256.54) (xy 223.52 256.54)
		)
		(stroke
			(width 0)
			(type default)
		)
	)
	(wire
		(pts
			(xy 148.59 109.22) (xy 179.07 109.22)
		)
		(stroke
			(width 0)
			(type default)
		)
	)
	(wire
		(pts
			(xy 226.06 160.02) (xy 262.89 160.02)
		)
		(stroke
			(width 0)
			(type default)
		)
	)
	(bus
		(pts
			(xy 224.79 121.92) (xy 224.79 128.27)
		)
		(stroke
			(width 0)
			(type default)
		)
	)
	(bus
		(pts
			(xy 224.79 231.14) (xy 224.79 237.49)
		)
		(stroke
			(width 0)
			(type default)
		)
	)
	(bus
		(pts
			(xy 147.32 231.14) (xy 147.32 233.68)
		)
		(stroke
			(width 0)
			(type default)
		)
	)
	(bus
		(pts
			(xy 147.32 66.04) (xy 147.32 74.93)
		)
		(stroke
			(width 0)
			(type default)
		)
	)
	(bus
		(pts
			(xy 147.32 247.65) (xy 147.32 255.27)
		)
		(stroke
			(width 0)
			(type default)
		)
	)
	(wire
		(pts
			(xy 186.69 78.74) (xy 223.52 78.74)
		)
		(stroke
			(width 0)
			(type default)
		)
	)
	(wire
		(pts
			(xy 226.06 123.19) (xy 260.35 123.19)
		)
		(stroke
			(width 0)
			(type default)
		)
	)
	(wire
		(pts
			(xy 226.06 129.54) (xy 260.35 129.54)
		)
		(stroke
			(width 0)
			(type default)
		)
	)
	(wire
		(pts
			(xy 148.59 218.44) (xy 223.52 218.44)
		)
		(stroke
			(width 0)
			(type default)
		)
	)
	(bus
		(pts
			(xy 147.32 257.81) (xy 147.32 260.35)
		)
		(stroke
			(width 0)
			(type default)
		)
	)
	(bus
		(pts
			(xy 147.32 100.33) (xy 147.32 102.87)
		)
		(stroke
			(width 0)
			(type default)
		)
	)
	(bus
		(pts
			(xy 224.79 102.87) (xy 224.79 105.41)
		)
		(stroke
			(width 0)
			(type default)
		)
	)
	(wire
		(pts
			(xy 186.69 146.05) (xy 223.52 146.05)
		)
		(stroke
			(width 0)
			(type default)
		)
	)
	(wire
		(pts
			(xy 148.59 196.85) (xy 223.52 196.85)
		)
		(stroke
			(width 0)
			(type default)
		)
	)
	(wire
		(pts
			(xy 260.35 53.34) (xy 226.06 53.34)
		)
		(stroke
			(width 0)
			(type default)
		)
	)
	(wire
		(pts
			(xy 279.4 59.69) (xy 279.4 62.23)
		)
		(stroke
			(width 0)
			(type default)
		)
	)
	(bus
		(pts
			(xy 147.32 135.89) (xy 147.32 144.78)
		)
		(stroke
			(width 0)
			(type default)
		)
	)
	(bus
		(pts
			(xy 147.32 242.57) (xy 147.32 245.11)
		)
		(stroke
			(width 0)
			(type default)
		)
	)
	(wire
		(pts
			(xy 279.4 78.74) (xy 279.4 81.28)
		)
		(stroke
			(width 0)
			(type default)
		)
	)
	(wire
		(pts
			(xy 148.59 137.16) (xy 179.07 137.16)
		)
		(stroke
			(width 0)
			(type default)
		)
	)
	(wire
		(pts
			(xy 148.59 115.57) (xy 179.07 115.57)
		)
		(stroke
			(width 0)
			(type default)
		)
	)
	(bus
		(pts
			(xy 147.32 128.27) (xy 147.32 130.81)
		)
		(stroke
			(width 0)
			(type default)
		)
	)
	(bus
		(pts
			(xy 147.32 158.75) (xy 147.32 161.29)
		)
		(stroke
			(width 0)
			(type default)
		)
	)
	(wire
		(pts
			(xy 279.4 129.54) (xy 279.4 132.08)
		)
		(stroke
			(width 0)
			(type default)
		)
	)
	(wire
		(pts
			(xy 226.06 87.63) (xy 260.35 87.63)
		)
		(stroke
			(width 0)
			(type default)
		)
	)
	(wire
		(pts
			(xy 226.06 90.17) (xy 260.35 90.17)
		)
		(stroke
			(width 0)
			(type default)
		)
	)
	(wire
		(pts
			(xy 226.06 109.22) (xy 260.35 109.22)
		)
		(stroke
			(width 0)
			(type default)
		)
	)
	(bus
		(pts
			(xy 224.79 252.73) (xy 224.79 255.27)
		)
		(stroke
			(width 0)
			(type default)
		)
	)
	(wire
		(pts
			(xy 148.59 90.17) (xy 179.07 90.17)
		)
		(stroke
			(width 0)
			(type default)
		)
	)
	(wire
		(pts
			(xy 189.23 59.69) (xy 223.52 59.69)
		)
		(stroke
			(width 0)
			(type default)
		)
	)
	(bus
		(pts
			(xy 147.32 29.21) (xy 147.32 44.45)
		)
		(stroke
			(width 0)
			(type default)
		)
	)
	(wire
		(pts
			(xy 270.51 109.22) (xy 279.4 109.22)
		)
		(stroke
			(width 0)
			(type default)
		)
	)
	(wire
		(pts
			(xy 270.51 48.26) (xy 279.4 48.26)
		)
		(stroke
			(width 0)
			(type default)
		)
	)
	(bus
		(pts
			(xy 224.79 114.3) (xy 224.79 116.84)
		)
		(stroke
			(width 0)
			(type default)
		)
	)
	(wire
		(pts
			(xy 226.06 106.68) (xy 260.35 106.68)
		)
		(stroke
			(width 0)
			(type default)
		)
	)
	(bus
		(pts
			(xy 224.79 105.41) (xy 224.79 107.95)
		)
		(stroke
			(width 0)
			(type default)
		)
	)
	(bus
		(pts
			(xy 147.32 63.5) (xy 147.32 66.04)
		)
		(stroke
			(width 0)
			(type default)
		)
	)
	(wire
		(pts
			(xy 226.06 101.6) (xy 260.35 101.6)
		)
		(stroke
			(width 0)
			(type default)
		)
	)
	(wire
		(pts
			(xy 148.59 259.08) (xy 223.52 259.08)
		)
		(stroke
			(width 0)
			(type default)
		)
	)
	(wire
		(pts
			(xy 189.23 53.34) (xy 223.52 53.34)
		)
		(stroke
			(width 0)
			(type default)
		)
	)
	(bus
		(pts
			(xy 224.79 130.81) (xy 224.79 133.35)
		)
		(stroke
			(width 0)
			(type default)
		)
	)
	(bus
		(pts
			(xy 147.32 217.17) (xy 147.32 219.71)
		)
		(stroke
			(width 0)
			(type default)
		)
	)
	(wire
		(pts
			(xy 267.97 176.53) (xy 279.4 176.53)
		)
		(stroke
			(width 0)
			(type default)
		)
	)
	(bus
		(pts
			(xy 147.32 86.36) (xy 147.32 88.9)
		)
		(stroke
			(width 0)
			(type default)
		)
	)
	(wire
		(pts
			(xy 270.51 106.68) (xy 279.4 106.68)
		)
		(stroke
			(width 0)
			(type default)
		)
	)
	(bus
		(pts
			(xy 147.32 233.68) (xy 147.32 240.03)
		)
		(stroke
			(width 0)
			(type default)
		)
	)
	(bus
		(pts
			(xy 147.32 29.21) (xy 146.05 27.94)
		)
		(stroke
			(width 0)
			(type default)
		)
	)
	(bus
		(pts
			(xy 224.79 119.38) (xy 224.79 121.92)
		)
		(stroke
			(width 0)
			(type default)
		)
	)
	(bus
		(pts
			(xy 224.79 63.5) (xy 224.79 66.04)
		)
		(stroke
			(width 0)
			(type default)
		)
	)
	(wire
		(pts
			(xy 267.97 76.2) (xy 279.4 76.2)
		)
		(stroke
			(width 0)
			(type default)
		)
	)
	(wire
		(pts
			(xy 279.4 76.2) (xy 279.4 78.74)
		)
		(stroke
			(width 0)
			(type default)
		)
	)
	(wire
		(pts
			(xy 189.23 67.31) (xy 223.52 67.31)
		)
		(stroke
			(width 0)
			(type default)
		)
	)
	(wire
		(pts
			(xy 226.06 162.56) (xy 262.89 162.56)
		)
		(stroke
			(width 0)
			(type default)
		)
	)
	(wire
		(pts
			(xy 279.4 176.53) (xy 279.4 178.435)
		)
		(stroke
			(width 0)
			(type default)
		)
	)
	(wire
		(pts
			(xy 279.4 123.19) (xy 279.4 129.54)
		)
		(stroke
			(width 0)
			(type default)
		)
	)
	(bus
		(pts
			(xy 224.79 80.01) (xy 224.79 86.36)
		)
		(stroke
			(width 0)
			(type default)
		)
	)
	(wire
		(pts
			(xy 270.51 101.6) (xy 279.4 101.6)
		)
		(stroke
			(width 0)
			(type default)
		)
	)
	(bus
		(pts
			(xy 147.32 147.32) (xy 147.32 158.75)
		)
		(stroke
			(width 0)
			(type default)
		)
	)
	(bus
		(pts
			(xy 147.32 172.72) (xy 147.32 175.26)
		)
		(stroke
			(width 0)
			(type default)
		)
	)
	(wire
		(pts
			(xy 148.59 261.62) (xy 223.52 261.62)
		)
		(stroke
			(width 0)
			(type default)
		)
	)
	(bus
		(pts
			(xy 224.79 190.5) (xy 224.79 193.04)
		)
		(stroke
			(width 0)
			(type default)
		)
	)
	(wire
		(pts
			(xy 279.4 92.71) (xy 279.4 95.25)
		)
		(stroke
			(width 0)
			(type default)
		)
	)
	(wire
		(pts
			(xy 148.59 229.87) (xy 223.52 229.87)
		)
		(stroke
			(width 0)
			(type default)
		)
	)
	(wire
		(pts
			(xy 189.23 123.19) (xy 223.52 123.19)
		)
		(stroke
			(width 0)
			(type default)
		)
	)
	(wire
		(pts
			(xy 279.4 45.72) (xy 279.4 48.26)
		)
		(stroke
			(width 0)
			(type default)
		)
	)
	(wire
		(pts
			(xy 148.59 199.39) (xy 223.52 199.39)
		)
		(stroke
			(width 0)
			(type default)
		)
	)
	(wire
		(pts
			(xy 267.97 78.74) (xy 279.4 78.74)
		)
		(stroke
			(width 0)
			(type default)
		)
	)
	(wire
		(pts
			(xy 267.97 81.28) (xy 279.4 81.28)
		)
		(stroke
			(width 0)
			(type default)
		)
	)
	(wire
		(pts
			(xy 148.59 148.59) (xy 181.61 148.59)
		)
		(stroke
			(width 0)
			(type default)
		)
	)
	(wire
		(pts
			(xy 279.4 160.02) (xy 279.4 162.56)
		)
		(stroke
			(width 0)
			(type default)
		)
	)
	(bus
		(pts
			(xy 147.32 205.74) (xy 147.32 212.09)
		)
		(stroke
			(width 0)
			(type default)
		)
	)
	(bus
		(pts
			(xy 224.79 46.99) (xy 224.79 49.53)
		)
		(stroke
			(width 0)
			(type default)
		)
	)
	(wire
		(pts
			(xy 189.23 50.8) (xy 223.52 50.8)
		)
		(stroke
			(width 0)
			(type default)
		)
	)
	(bus
		(pts
			(xy 226.06 20.32) (xy 327.66 20.32)
		)
		(stroke
			(width 0)
			(type default)
		)
	)
	(bus
		(pts
			(xy 224.79 21.59) (xy 226.06 20.32)
		)
		(stroke
			(width 0)
			(type default)
		)
	)
	(wire
		(pts
			(xy 279.4 146.05) (xy 279.4 148.59)
		)
		(stroke
			(width 0)
			(type default)
		)
	)
	(bus
		(pts
			(xy 224.79 257.81) (xy 224.79 260.35)
		)
		(stroke
			(width 0)
			(type default)
		)
	)
	(wire
		(pts
			(xy 148.59 95.25) (xy 179.07 95.25)
		)
		(stroke
			(width 0)
			(type default)
		)
	)
	(bus
		(pts
			(xy 147.32 266.7) (xy 146.05 267.97)
		)
		(stroke
			(width 0)
			(type default)
		)
	)
	(bus
		(pts
			(xy 128.27 267.97) (xy 146.05 267.97)
		)
		(stroke
			(width 0)
			(type default)
		)
	)
	(bus
		(pts
			(xy 147.32 195.58) (xy 147.32 198.12)
		)
		(stroke
			(width 0)
			(type default)
		)
	)
	(wire
		(pts
			(xy 270.51 87.63) (xy 279.4 87.63)
		)
		(stroke
			(width 0)
			(type default)
		)
	)
	(wire
		(pts
			(xy 279.4 104.14) (xy 279.4 106.68)
		)
		(stroke
			(width 0)
			(type default)
		)
	)
	(bus
		(pts
			(xy 147.32 130.81) (xy 147.32 133.35)
		)
		(stroke
			(width 0)
			(type default)
		)
	)
	(wire
		(pts
			(xy 226.06 67.31) (xy 260.35 67.31)
		)
		(stroke
			(width 0)
			(type default)
		)
	)
	(wire
		(pts
			(xy 148.59 78.74) (xy 181.61 78.74)
		)
		(stroke
			(width 0)
			(type default)
		)
	)
	(wire
		(pts
			(xy 226.06 81.28) (xy 262.89 81.28)
		)
		(stroke
			(width 0)
			(type default)
		)
	)
	(wire
		(pts
			(xy 270.51 53.34) (xy 279.4 53.34)
		)
		(stroke
			(width 0)
			(type default)
		)
	)
	(wire
		(pts
			(xy 279.4 137.16) (xy 279.4 146.05)
		)
		(stroke
			(width 0)
			(type default)
		)
	)
	(wire
		(pts
			(xy 270.51 92.71) (xy 279.4 92.71)
		)
		(stroke
			(width 0)
			(type default)
		)
	)
	(wire
		(pts
			(xy 279.4 90.17) (xy 279.4 92.71)
		)
		(stroke
			(width 0)
			(type default)
		)
	)
	(bus
		(pts
			(xy 224.79 195.58) (xy 224.79 198.12)
		)
		(stroke
			(width 0)
			(type default)
		)
	)
	(wire
		(pts
			(xy 189.23 115.57) (xy 223.52 115.57)
		)
		(stroke
			(width 0)
			(type default)
		)
	)
	(bus
		(pts
			(xy 147.32 49.53) (xy 147.32 52.07)
		)
		(stroke
			(width 0)
			(type default)
		)
	)
	(wire
		(pts
			(xy 189.23 109.22) (xy 223.52 109.22)
		)
		(stroke
			(width 0)
			(type default)
		)
	)
	(bus
		(pts
			(xy 147.32 105.41) (xy 147.32 107.95)
		)
		(stroke
			(width 0)
			(type default)
		)
	)
	(wire
		(pts
			(xy 148.59 48.26) (xy 179.07 48.26)
		)
		(stroke
			(width 0)
			(type default)
		)
	)
	(wire
		(pts
			(xy 148.59 123.19) (xy 179.07 123.19)
		)
		(stroke
			(width 0)
			(type default)
		)
	)
	(bus
		(pts
			(xy 224.79 203.2) (xy 224.79 209.55)
		)
		(stroke
			(width 0)
			(type default)
		)
	)
	(bus
		(pts
			(xy 224.79 237.49) (xy 224.79 240.03)
		)
		(stroke
			(width 0)
			(type default)
		)
	)
	(bus
		(pts
			(xy 147.32 200.66) (xy 147.32 203.2)
		)
		(stroke
			(width 0)
			(type default)
		)
	)
	(wire
		(pts
			(xy 148.59 146.05) (xy 181.61 146.05)
		)
		(stroke
			(width 0)
			(type default)
		)
	)
	(bus
		(pts
			(xy 224.79 242.57) (xy 224.79 245.11)
		)
		(stroke
			(width 0)
			(type default)
		)
	)
	(wire
		(pts
			(xy 189.23 62.23) (xy 223.52 62.23)
		)
		(stroke
			(width 0)
			(type default)
		)
	)
	(bus
		(pts
			(xy 147.32 116.84) (xy 147.32 119.38)
		)
		(stroke
			(width 0)
			(type default)
		)
	)
	(bus
		(pts
			(xy 147.32 58.42) (xy 147.32 60.96)
		)
		(stroke
			(width 0)
			(type default)
		)
	)
	(wire
		(pts
			(xy 189.23 132.08) (xy 223.52 132.08)
		)
		(stroke
			(width 0)
			(type default)
		)
	)
	(wire
		(pts
			(xy 148.59 246.38) (xy 223.52 246.38)
		)
		(stroke
			(width 0)
			(type default)
		)
	)
	(wire
		(pts
			(xy 270.51 50.8) (xy 279.4 50.8)
		)
		(stroke
			(width 0)
			(type default)
		)
	)
	(bus
		(pts
			(xy 147.32 193.04) (xy 147.32 195.58)
		)
		(stroke
			(width 0)
			(type default)
		)
	)
	(wire
		(pts
			(xy 189.23 48.26) (xy 223.52 48.26)
		)
		(stroke
			(width 0)
			(type default)
		)
	)
	(bus
		(pts
			(xy 147.32 240.03) (xy 147.32 242.57)
		)
		(stroke
			(width 0)
			(type default)
		)
	)
	(bus
		(pts
			(xy 224.79 198.12) (xy 224.79 200.66)
		)
		(stroke
			(width 0)
			(type default)
		)
	)
	(wire
		(pts
			(xy 270.51 123.19) (xy 279.4 123.19)
		)
		(stroke
			(width 0)
			(type default)
		)
	)
	(bus
		(pts
			(xy 147.32 93.98) (xy 147.32 100.33)
		)
		(stroke
			(width 0)
			(type default)
		)
	)
	(wire
		(pts
			(xy 189.23 129.54) (xy 223.52 129.54)
		)
		(stroke
			(width 0)
			(type default)
		)
	)
	(wire
		(pts
			(xy 148.59 81.28) (xy 181.61 81.28)
		)
		(stroke
			(width 0)
			(type default)
		)
	)
	(wire
		(pts
			(xy 226.06 146.05) (xy 262.89 146.05)
		)
		(stroke
			(width 0)
			(type default)
		)
	)
	(bus
		(pts
			(xy 147.32 144.78) (xy 147.32 147.32)
		)
		(stroke
			(width 0)
			(type default)
		)
	)
	(wire
		(pts
			(xy 226.06 76.2) (xy 262.89 76.2)
		)
		(stroke
			(width 0)
			(type default)
		)
	)
	(wire
		(pts
			(xy 279.4 115.57) (xy 279.4 118.11)
		)
		(stroke
			(width 0)
			(type default)
		)
	)
	(bus
		(pts
			(xy 224.79 77.47) (xy 224.79 80.01)
		)
		(stroke
			(width 0)
			(type default)
		)
	)
	(bus
		(pts
			(xy 224.79 255.27) (xy 224.79 257.81)
		)
		(stroke
			(width 0)
			(type default)
		)
	)
	(bus
		(pts
			(xy 224.79 223.52) (xy 224.79 226.06)
		)
		(stroke
			(width 0)
			(type default)
		)
	)
	(bus
		(pts
			(xy 224.79 200.66) (xy 224.79 203.2)
		)
		(stroke
			(width 0)
			(type default)
		)
	)
	(bus
		(pts
			(xy 224.79 193.04) (xy 224.79 195.58)
		)
		(stroke
			(width 0)
			(type default)
		)
	)
	(wire
		(pts
			(xy 279.4 106.68) (xy 279.4 109.22)
		)
		(stroke
			(width 0)
			(type default)
		)
	)
	(wire
		(pts
			(xy 189.23 106.68) (xy 223.52 106.68)
		)
		(stroke
			(width 0)
			(type default)
		)
	)
	(wire
		(pts
			(xy 226.06 173.99) (xy 262.89 173.99)
		)
		(stroke
			(width 0)
			(type default)
		)
	)
	(bus
		(pts
			(xy 224.79 86.36) (xy 224.79 88.9)
		)
		(stroke
			(width 0)
			(type default)
		)
	)
	(wire
		(pts
			(xy 279.4 120.65) (xy 279.4 123.19)
		)
		(stroke
			(width 0)
			(type default)
		)
	)
	(wire
		(pts
			(xy 279.4 53.34) (xy 279.4 59.69)
		)
		(stroke
			(width 0)
			(type default)
		)
	)
	(bus
		(pts
			(xy 147.32 133.35) (xy 147.32 135.89)
		)
		(stroke
			(width 0)
			(type default)
		)
	)
	(bus
		(pts
			(xy 224.79 147.32) (xy 224.79 158.75)
		)
		(stroke
			(width 0)
			(type default)
		)
	)
	(bus
		(pts
			(xy 147.32 255.27) (xy 147.32 257.81)
		)
		(stroke
			(width 0)
			(type default)
		)
	)
	(bus
		(pts
			(xy 224.79 66.04) (xy 224.79 74.93)
		)
		(stroke
			(width 0)
			(type default)
		)
	)
	(wire
		(pts
			(xy 148.59 101.6) (xy 179.07 101.6)
		)
		(stroke
			(width 0)
			(type default)
		)
	)
	(wire
		(pts
			(xy 189.23 134.62) (xy 223.52 134.62)
		)
		(stroke
			(width 0)
			(type default)
		)
	)
	(bus
		(pts
			(xy 224.79 144.78) (xy 224.79 147.32)
		)
		(stroke
			(width 0)
			(type default)
		)
	)
	(wire
		(pts
			(xy 148.59 59.69) (xy 179.07 59.69)
		)
		(stroke
			(width 0)
			(type default)
		)
	)
	(bus
		(pts
			(xy 224.79 161.29) (xy 224.79 172.72)
		)
		(stroke
			(width 0)
			(type default)
		)
	)
	(wire
		(pts
			(xy 260.35 50.8) (xy 226.06 50.8)
		)
		(stroke
			(width 0)
			(type default)
		)
	)
	(bus
		(pts
			(xy 224.79 135.89) (xy 224.79 144.78)
		)
		(stroke
			(width 0)
			(type default)
		)
	)
	(bus
		(pts
			(xy 224.79 74.93) (xy 224.79 77.47)
		)
		(stroke
			(width 0)
			(type default)
		)
	)
	(wire
		(pts
			(xy 189.23 137.16) (xy 223.52 137.16)
		)
		(stroke
			(width 0)
			(type default)
		)
	)
	(bus
		(pts
			(xy 147.32 226.06) (xy 147.32 228.6)
		)
		(stroke
			(width 0)
			(type default)
		)
	)
	(wire
		(pts
			(xy 226.06 115.57) (xy 260.35 115.57)
		)
		(stroke
			(width 0)
			(type default)
		)
	)
	(wire
		(pts
			(xy 148.59 129.54) (xy 179.07 129.54)
		)
		(stroke
			(width 0)
			(type default)
		)
	)
	(bus
		(pts
			(xy 224.79 93.98) (xy 224.79 100.33)
		)
		(stroke
			(width 0)
			(type default)
		)
	)
	(wire
		(pts
			(xy 267.97 173.99) (xy 279.4 173.99)
		)
		(stroke
			(width 0)
			(type default)
		)
	)
	(bus
		(pts
			(xy 224.79 187.96) (xy 226.06 186.69)
		)
		(stroke
			(width 0)
			(type default)
		)
	)
	(wire
		(pts
			(xy 148.59 215.9) (xy 223.52 215.9)
		)
		(stroke
			(width 0)
			(type default)
		)
	)
	(wire
		(pts
			(xy 148.59 210.82) (xy 223.52 210.82)
		)
		(stroke
			(width 0)
			(type default)
		)
	)
	(bus
		(pts
			(xy 224.79 214.63) (xy 224.79 217.17)
		)
		(stroke
			(width 0)
			(type default)
		)
	)
	(bus
		(pts
			(xy 147.32 228.6) (xy 147.32 231.14)
		)
		(stroke
			(width 0)
			(type default)
		)
	)
	(bus
		(pts
			(xy 224.79 49.53) (xy 224.79 52.07)
		)
		(stroke
			(width 0)
			(type default)
		)
	)
	(wire
		(pts
			(xy 270.51 137.16) (xy 279.4 137.16)
		)
		(stroke
			(width 0)
			(type default)
		)
	)
	(wire
		(pts
			(xy 279.4 67.31) (xy 279.4 76.2)
		)
		(stroke
			(width 0)
			(type default)
		)
	)
	(wire
		(pts
			(xy 148.59 87.63) (xy 179.07 87.63)
		)
		(stroke
			(width 0)
			(type default)
		)
	)
	(label "LPDDR5_IN.CA0"
		(at 154.94 92.71 0)
		(effects
			(font
				(size 1.27 1.27)
			)
			(justify left bottom)
		)
	)
	(label "LPDDR5_DIE.CA5"
		(at 200.66 109.22 0)
		(effects
			(font
				(size 1.27 1.27)
			)
			(justify left bottom)
		)
	)
	(label "LPDDR5_DIE.CK_N"
		(at 234.95 173.99 0)
		(effects
			(font
				(size 1.27 1.27)
			)
			(justify left bottom)
		)
	)
	(label "LPDDR5_DIE.RDQS0_P"
		(at 200.66 256.54 0)
		(effects
			(font
				(size 1.27 1.27)
			)
			(justify left bottom)
		)
	)
	(label "LPDDR5_DIE.DQ5"
		(at 234.95 59.69 0)
		(effects
			(font
				(size 1.27 1.27)
			)
			(justify left bottom)
		)
	)
	(label "LPDDR5_DIE.CA0"
		(at 234.95 92.71 0)
		(effects
			(font
				(size 1.27 1.27)
			)
			(justify left bottom)
		)
	)
	(label "LPDDR5_DIE.CA6"
		(at 234.95 78.74 0)
		(effects
			(font
				(size 1.27 1.27)
			)
			(justify left bottom)
		)
	)
	(label "LPDDR5_DIE.CA4"
		(at 234.95 106.68 0)
		(effects
			(font
				(size 1.27 1.27)
			)
			(justify left bottom)
		)
	)
	(label "LPDDR5_DIE.DQ15"
		(at 200.66 129.54 0)
		(effects
			(font
				(size 1.27 1.27)
			)
			(justify left bottom)
		)
	)
	(label "LPDDR5_IN.DQ7"
		(at 154.94 67.31 0)
		(effects
			(font
				(size 1.27 1.27)
			)
			(justify left bottom)
		)
	)
	(label "LPDDR5_IN.CA4"
		(at 154.94 106.68 0)
		(effects
			(font
				(size 1.27 1.27)
			)
			(justify left bottom)
		)
	)
	(label "LPDDR5_DIE.DQ1"
		(at 234.95 48.26 0)
		(effects
			(font
				(size 1.27 1.27)
			)
			(justify left bottom)
		)
	)
	(label "LPDDR5_IN.CA1"
		(at 154.94 95.25 0)
		(effects
			(font
				(size 1.27 1.27)
			)
			(justify left bottom)
		)
	)
	(label "LPDDR5_IN.DQ1"
		(at 154.94 48.26 0)
		(effects
			(font
				(size 1.27 1.27)
			)
			(justify left bottom)
		)
	)
	(label "LPDDR5_DIE.DQ10"
		(at 200.66 229.87 0)
		(effects
			(font
				(size 1.27 1.27)
			)
			(justify left bottom)
		)
	)
	(label "LPDDR5_OUT.DQ8"
		(at 153.67 224.79 0)
		(effects
			(font
				(size 1.27 1.27)
			)
			(justify left bottom)
		)
	)
	(label "LPDDR5_DIE.DMI1"
		(at 200.66 76.2 0)
		(effects
			(font
				(size 1.27 1.27)
			)
			(justify left bottom)
		)
	)
	(label "LPDDR5_OUT.DQ0"
		(at 153.67 196.85 0)
		(effects
			(font
				(size 1.27 1.27)
			)
			(justify left bottom)
		)
	)
	(label "LPDDR5_OUT.RDQS0_N"
		(at 153.67 254 0)
		(effects
			(font
				(size 1.27 1.27)
			)
			(justify left bottom)
		)
	)
	(label "LPDDR5_DIE.WCK0_P"
		(at 200.66 148.59 0)
		(effects
			(font
				(size 1.27 1.27)
			)
			(justify left bottom)
		)
	)
	(label "LPDDR5_DIE.WCK0_P"
		(at 234.95 148.59 0)
		(effects
			(font
				(size 1.27 1.27)
			)
			(justify left bottom)
		)
	)
	(label "LPDDR5_IN.CA3"
		(at 154.94 104.14 0)
		(effects
			(font
				(size 1.27 1.27)
			)
			(justify left bottom)
		)
	)
	(label "LPDDR5_DIE.CA5"
		(at 234.95 109.22 0)
		(effects
			(font
				(size 1.27 1.27)
			)
			(justify left bottom)
		)
	)
	(label "LPDDR5_OUT.DQ9"
		(at 153.67 227.33 0)
		(effects
			(font
				(size 1.27 1.27)
			)
			(justify left bottom)
		)
	)
	(label "LPDDR5_DIE.DQ15"
		(at 200.66 246.38 0)
		(effects
			(font
				(size 1.27 1.27)
			)
			(justify left bottom)
		)
	)
	(label "LPDDR5_DIE.CA4"
		(at 200.66 106.68 0)
		(effects
			(font
				(size 1.27 1.27)
			)
			(justify left bottom)
		)
	)
	(label "LPDDR5_IN.DQ13"
		(at 154.94 137.16 0)
		(effects
			(font
				(size 1.27 1.27)
			)
			(justify left bottom)
		)
	)
	(label "LPDDR5_IN.CS1"
		(at 154.94 90.17 0)
		(effects
			(font
				(size 1.27 1.27)
			)
			(justify left bottom)
		)
	)
	(label "LPDDR5_DIE.DQ6"
		(at 234.95 64.77 0)
		(effects
			(font
				(size 1.27 1.27)
			)
			(justify left bottom)
		)
	)
	(label "LPDDR5_DIE.DQ5"
		(at 200.66 213.36 0)
		(effects
			(font
				(size 1.27 1.27)
			)
			(justify left bottom)
		)
	)
	(label "LPDDR5_IN.DQ12"
		(at 154.94 134.62 0)
		(effects
			(font
				(size 1.27 1.27)
			)
			(justify left bottom)
		)
	)
	(label "LPDDR5_DIE.DQ9"
		(at 200.66 227.33 0)
		(effects
			(font
				(size 1.27 1.27)
			)
			(justify left bottom)
		)
	)
	(label "LPDDR5_DIE.CA3"
		(at 234.95 104.14 0)
		(effects
			(font
				(size 1.27 1.27)
			)
			(justify left bottom)
		)
	)
	(label "LPDDR5_DIE.DQ4"
		(at 200.66 210.82 0)
		(effects
			(font
				(size 1.27 1.27)
			)
			(justify left bottom)
		)
	)
	(label "LPDDR5_DIE.DQ6"
		(at 200.66 215.9 0)
		(effects
			(font
				(size 1.27 1.27)
			)
			(justify left bottom)
		)
	)
	(label "LPDDR5_OUT.DQ12"
		(at 153.67 238.76 0)
		(effects
			(font
				(size 1.27 1.27)
			)
			(justify left bottom)
		)
	)
	(label "LPDDR5_DIE.DQ3"
		(at 234.95 45.72 0)
		(effects
			(font
				(size 1.27 1.27)
			)
			(justify left bottom)
		)
	)
	(label "LPDDR5_OUT.DQ15"
		(at 153.67 246.38 0)
		(effects
			(font
				(size 1.27 1.27)
			)
			(justify left bottom)
		)
	)
	(label "LPDDR5_DIE.CA1"
		(at 200.66 95.25 0)
		(effects
			(font
				(size 1.27 1.27)
			)
			(justify left bottom)
		)
	)
	(label "LPDDR5_OUT.DQ3"
		(at 153.67 204.47 0)
		(effects
			(font
				(size 1.27 1.27)
			)
			(justify left bottom)
		)
	)
	(label "LPDDR5_IN.DQ4"
		(at 154.94 62.23 0)
		(effects
			(font
				(size 1.27 1.27)
			)
			(justify left bottom)
		)
	)
	(label "LPDDR5_IN.WCK0_N"
		(at 154.94 146.05 0)
		(effects
			(font
				(size 1.27 1.27)
			)
			(justify left bottom)
		)
	)
	(label "LPDDR5_DIE.DQ9"
		(at 234.95 120.65 0)
		(effects
			(font
				(size 1.27 1.27)
			)
			(justify left bottom)
		)
	)
	(label "LPDDR5_DIE.DQ5"
		(at 200.66 59.69 0)
		(effects
			(font
				(size 1.27 1.27)
			)
			(justify left bottom)
		)
	)
	(label "LPDDR5_DIE.CK_P"
		(at 234.95 176.53 0)
		(effects
			(font
				(size 1.27 1.27)
			)
			(justify left bottom)
		)
	)
	(label "LPDDR5_DIE.DQ11"
		(at 200.66 232.41 0)
		(effects
			(font
				(size 1.27 1.27)
			)
			(justify left bottom)
		)
	)
	(label "LPDDR5_DIE.DMI0"
		(at 200.66 81.28 0)
		(effects
			(font
				(size 1.27 1.27)
			)
			(justify left bottom)
		)
	)
	(label "LPDDR5_DIE.DMI0"
		(at 234.95 81.28 0)
		(effects
			(font
				(size 1.27 1.27)
			)
			(justify left bottom)
		)
	)
	(label "LPDDR5_IN.DQ5"
		(at 154.94 59.69 0)
		(effects
			(font
				(size 1.27 1.27)
			)
			(justify left bottom)
		)
	)
	(label "LPDDR5_DIE.WCK0_N"
		(at 234.95 146.05 0)
		(effects
			(font
				(size 1.27 1.27)
			)
			(justify left bottom)
		)
	)
	(label "LPDDR5_DIE.DQ3"
		(at 200.66 204.47 0)
		(effects
			(font
				(size 1.27 1.27)
			)
			(justify left bottom)
		)
	)
	(label "LPDDR5_IN.DQ9"
		(at 154.94 120.65 0)
		(effects
			(font
				(size 1.27 1.27)
			)
			(justify left bottom)
		)
	)
	(label "LPDDR5_OUT.RDQS1_P"
		(at 153.67 261.62 0)
		(effects
			(font
				(size 1.27 1.27)
			)
			(justify left bottom)
		)
	)
	(label "LPDDR5_DIE.DQ0"
		(at 200.66 196.85 0)
		(effects
			(font
				(size 1.27 1.27)
			)
			(justify left bottom)
		)
	)
	(label "LPDDR5_OUT.DQ10"
		(at 153.67 229.87 0)
		(effects
			(font
				(size 1.27 1.27)
			)
			(justify left bottom)
		)
	)
	(label "LPDDR5_DIE.WCK1_N"
		(at 234.95 160.02 0)
		(effects
			(font
				(size 1.27 1.27)
			)
			(justify left bottom)
		)
	)
	(label "LPDDR5_DIE.CK_P"
		(at 200.66 176.53 0)
		(effects
			(font
				(size 1.27 1.27)
			)
			(justify left bottom)
		)
	)
	(label "LPDDR5_DIE.DQ1"
		(at 200.66 48.26 0)
		(effects
			(font
				(size 1.27 1.27)
			)
			(justify left bottom)
		)
	)
	(label "LPDDR5_DIE.RDQS1_N"
		(at 200.66 259.08 0)
		(effects
			(font
				(size 1.27 1.27)
			)
			(justify left bottom)
		)
	)
	(label "LPDDR5_DIE.CS0"
		(at 234.95 87.63 0)
		(effects
			(font
				(size 1.27 1.27)
			)
			(justify left bottom)
		)
	)
	(label "LPDDR5_DIE.DQ13"
		(at 234.95 137.16 0)
		(effects
			(font
				(size 1.27 1.27)
			)
			(justify left bottom)
		)
	)
	(label "LPDDR5_OUT.DQ4"
		(at 153.67 210.82 0)
		(effects
			(font
				(size 1.27 1.27)
			)
			(justify left bottom)
		)
	)
	(label "LPDDR5_DIE.DQ10"
		(at 200.66 118.11 0)
		(effects
			(font
				(size 1.27 1.27)
			)
			(justify left bottom)
		)
	)
	(label "LPDDR5_DIE.CA2"
		(at 234.95 101.6 0)
		(effects
			(font
				(size 1.27 1.27)
			)
			(justify left bottom)
		)
	)
	(label "LPDDR5_DIE.DQ13"
		(at 200.66 137.16 0)
		(effects
			(font
				(size 1.27 1.27)
			)
			(justify left bottom)
		)
	)
	(label "LPDDR5_IN.CA6"
		(at 154.94 78.74 0)
		(effects
			(font
				(size 1.27 1.27)
			)
			(justify left bottom)
		)
	)
	(label "LPDDR5_IN.CS0"
		(at 154.94 87.63 0)
		(effects
			(font
				(size 1.27 1.27)
			)
			(justify left bottom)
		)
	)
	(label "LPDDR5_IN.WCK1_N"
		(at 154.94 160.02 0)
		(effects
			(font
				(size 1.27 1.27)
			)
			(justify left bottom)
		)
	)
	(label "LPDDR5_OUT.DQ14"
		(at 153.67 243.84 0)
		(effects
			(font
				(size 1.27 1.27)
			)
			(justify left bottom)
		)
	)
	(label "LPDDR5_DIE.DQ4"
		(at 234.95 62.23 0)
		(effects
			(font
				(size 1.27 1.27)
			)
			(justify left bottom)
		)
	)
	(label "LPDDR5_DIE.RDQS1_P"
		(at 200.66 261.62 0)
		(effects
			(font
				(size 1.27 1.27)
			)
			(justify left bottom)
		)
	)
	(label "LPDDR5_IN.DQ14"
		(at 154.94 132.08 0)
		(effects
			(font
				(size 1.27 1.27)
			)
			(justify left bottom)
		)
	)
	(label "LPDDR5_IN.CK_P"
		(at 154.94 176.53 0)
		(effects
			(font
				(size 1.27 1.27)
			)
			(justify left bottom)
		)
	)
	(label "LPDDR5_DIE.CA0"
		(at 200.66 92.71 0)
		(effects
			(font
				(size 1.27 1.27)
			)
			(justify left bottom)
		)
	)
	(label "LPDDR5_DIE.DQ14"
		(at 234.95 132.08 0)
		(effects
			(font
				(size 1.27 1.27)
			)
			(justify left bottom)
		)
	)
	(label "LPDDR5_IN.WCK0_P"
		(at 154.94 148.59 0)
		(effects
			(font
				(size 1.27 1.27)
			)
			(justify left bottom)
		)
	)
	(label "LPDDR5_DIE.DQ9"
		(at 200.66 120.65 0)
		(effects
			(font
				(size 1.27 1.27)
			)
			(justify left bottom)
		)
	)
	(label "LPDDR5_OUT.DQ2"
		(at 153.67 201.93 0)
		(effects
			(font
				(size 1.27 1.27)
			)
			(justify left bottom)
		)
	)
	(label "LPDDR5_OUT.DQ7"
		(at 153.67 218.44 0)
		(effects
			(font
				(size 1.27 1.27)
			)
			(justify left bottom)
		)
	)
	(label "LPDDR5_DIE.DQ3"
		(at 200.66 45.72 0)
		(effects
			(font
				(size 1.27 1.27)
			)
			(justify left bottom)
		)
	)
	(label "LPDDR5_IN.CK_N"
		(at 154.94 173.99 0)
		(effects
			(font
				(size 1.27 1.27)
			)
			(justify left bottom)
		)
	)
	(label "LPDDR5_DIE.DQ11"
		(at 234.95 123.19 0)
		(effects
			(font
				(size 1.27 1.27)
			)
			(justify left bottom)
		)
	)
	(label "LPDDR5_DIE.DQ12"
		(at 200.66 238.76 0)
		(effects
			(font
				(size 1.27 1.27)
			)
			(justify left bottom)
		)
	)
	(label "LPDDR5_DIE.CA6"
		(at 200.66 78.74 0)
		(effects
			(font
				(size 1.27 1.27)
			)
			(justify left bottom)
		)
	)
	(label "LPDDR5_DIE.CS1"
		(at 234.95 90.17 0)
		(effects
			(font
				(size 1.27 1.27)
			)
			(justify left bottom)
		)
	)
	(label "LPDDR5_OUT.DQ5"
		(at 153.67 213.36 0)
		(effects
			(font
				(size 1.27 1.27)
			)
			(justify left bottom)
		)
	)
	(label "LPDDR5_IN.DQ11"
		(at 154.94 123.19 0)
		(effects
			(font
				(size 1.27 1.27)
			)
			(justify left bottom)
		)
	)
	(label "LPDDR5_IN.CA5"
		(at 154.94 109.22 0)
		(effects
			(font
				(size 1.27 1.27)
			)
			(justify left bottom)
		)
	)
	(label "LPDDR5_IN.DQ6"
		(at 154.94 64.77 0)
		(effects
			(font
				(size 1.27 1.27)
			)
			(justify left bottom)
		)
	)
	(label "LPDDR5_DIE.DQ8"
		(at 200.66 115.57 0)
		(effects
			(font
				(size 1.27 1.27)
			)
			(justify left bottom)
		)
	)
	(label "LPDDR5_IN.DQ10"
		(at 154.94 118.11 0)
		(effects
			(font
				(size 1.27 1.27)
			)
			(justify left bottom)
		)
	)
	(label "LPDDR5_DIE.DQ1"
		(at 200.66 199.39 0)
		(effects
			(font
				(size 1.27 1.27)
			)
			(justify left bottom)
		)
	)
	(label "LPDDR5_OUT.RDQS1_N"
		(at 153.67 259.08 0)
		(effects
			(font
				(size 1.27 1.27)
			)
			(justify left bottom)
		)
	)
	(label "LPDDR5_DIE.DQ8"
		(at 200.66 224.79 0)
		(effects
			(font
				(size 1.27 1.27)
			)
			(justify left bottom)
		)
	)
	(label "LPDDR5_DIE.DQ7"
		(at 200.66 67.31 0)
		(effects
			(font
				(size 1.27 1.27)
			)
			(justify left bottom)
		)
	)
	(label "LPDDR5_DIE.DQ12"
		(at 200.66 134.62 0)
		(effects
			(font
				(size 1.27 1.27)
			)
			(justify left bottom)
		)
	)
	(label "LPDDR5_DIE.DQ7"
		(at 234.95 67.31 0)
		(effects
			(font
				(size 1.27 1.27)
			)
			(justify left bottom)
		)
	)
	(label "LPDDR5_DIE.DQ2"
		(at 200.66 201.93 0)
		(effects
			(font
				(size 1.27 1.27)
			)
			(justify left bottom)
		)
	)
	(label "LPDDR5_DIE.DQ14"
		(at 200.66 243.84 0)
		(effects
			(font
				(size 1.27 1.27)
			)
			(justify left bottom)
		)
	)
	(label "LPDDR5_IN.CA2"
		(at 154.94 101.6 0)
		(effects
			(font
				(size 1.27 1.27)
			)
			(justify left bottom)
		)
	)
	(label "LPDDR5_IN.DQ0"
		(at 154.94 53.34 0)
		(effects
			(font
				(size 1.27 1.27)
			)
			(justify left bottom)
		)
	)
	(label "LPDDR5_IN.WCK1_P"
		(at 154.94 162.56 0)
		(effects
			(font
				(size 1.27 1.27)
			)
			(justify left bottom)
		)
	)
	(label "LPDDR5_DIE.DQ11"
		(at 200.66 123.19 0)
		(effects
			(font
				(size 1.27 1.27)
			)
			(justify left bottom)
		)
	)
	(label "LPDDR5_IN.DMI1"
		(at 154.94 76.2 0)
		(effects
			(font
				(size 1.27 1.27)
			)
			(justify left bottom)
		)
	)
	(label "LPDDR5_DIE.DQ15"
		(at 234.95 129.54 0)
		(effects
			(font
				(size 1.27 1.27)
			)
			(justify left bottom)
		)
	)
	(label "LPDDR5_DIE.CK_N"
		(at 200.66 173.99 0)
		(effects
			(font
				(size 1.27 1.27)
			)
			(justify left bottom)
		)
	)
	(label "LPDDR5_OUT.DQ13"
		(at 153.67 241.3 0)
		(effects
			(font
				(size 1.27 1.27)
			)
			(justify left bottom)
		)
	)
	(label "LPDDR5_DIE.CA2"
		(at 200.66 101.6 0)
		(effects
			(font
				(size 1.27 1.27)
			)
			(justify left bottom)
		)
	)
	(label "LPDDR5_DIE.DQ6"
		(at 200.66 64.77 0)
		(effects
			(font
				(size 1.27 1.27)
			)
			(justify left bottom)
		)
	)
	(label "LPDDR5_IN.DQ2"
		(at 154.94 50.8 0)
		(effects
			(font
				(size 1.27 1.27)
			)
			(justify left bottom)
		)
	)
	(label "LPDDR5_DIE.CA1"
		(at 234.95 95.25 0)
		(effects
			(font
				(size 1.27 1.27)
			)
			(justify left bottom)
		)
	)
	(label "LPDDR5_OUT.DMI1"
		(at 153.67 194.31 0)
		(effects
			(font
				(size 1.27 1.27)
			)
			(justify left bottom)
		)
	)
	(label "LPDDR5_IN.DMI0"
		(at 154.94 81.28 0)
		(effects
			(font
				(size 1.27 1.27)
			)
			(justify left bottom)
		)
	)
	(label "LPDDR5_IN.DQ3"
		(at 154.94 45.72 0)
		(effects
			(font
				(size 1.27 1.27)
			)
			(justify left bottom)
		)
	)
	(label "LPDDR5_IN.DQ15"
		(at 154.94 129.54 0)
		(effects
			(font
				(size 1.27 1.27)
			)
			(justify left bottom)
		)
	)
	(label "LPDDR5_OUT.RDQS0_P"
		(at 153.67 256.54 0)
		(effects
			(font
				(size 1.27 1.27)
			)
			(justify left bottom)
		)
	)
	(label "LPDDR5_DIE.CA3"
		(at 200.66 104.14 0)
		(effects
			(font
				(size 1.27 1.27)
			)
			(justify left bottom)
		)
	)
	(label "LPDDR5_DIE.DQ7"
		(at 200.66 218.44 0)
		(effects
			(font
				(size 1.27 1.27)
			)
			(justify left bottom)
		)
	)
	(label "LPDDR5_DIE.WCK1_N"
		(at 200.66 160.02 0)
		(effects
			(font
				(size 1.27 1.27)
			)
			(justify left bottom)
		)
	)
	(label "LPDDR5_DIE.DQ13"
		(at 200.66 241.3 0)
		(effects
			(font
				(size 1.27 1.27)
			)
			(justify left bottom)
		)
	)
	(label "LPDDR5_IN.DQ8"
		(at 154.94 115.57 0)
		(effects
			(font
				(size 1.27 1.27)
			)
			(justify left bottom)
		)
	)
	(label "LPDDR5_DIE.RDQS0_N"
		(at 200.66 254 0)
		(effects
			(font
				(size 1.27 1.27)
			)
			(justify left bottom)
		)
	)
	(label "LPDDR5_DIE.DQ2"
		(at 200.66 50.8 0)
		(effects
			(font
				(size 1.27 1.27)
			)
			(justify left bottom)
		)
	)
	(label "LPDDR5_DIE.DQ12"
		(at 234.95 134.62 0)
		(effects
			(font
				(size 1.27 1.27)
			)
			(justify left bottom)
		)
	)
	(label "LPDDR5_OUT.DQ6"
		(at 153.67 215.9 0)
		(effects
			(font
				(size 1.27 1.27)
			)
			(justify left bottom)
		)
	)
	(label "LPDDR5_DIE.DQ0"
		(at 234.95 53.34 0)
		(effects
			(font
				(size 1.27 1.27)
			)
			(justify left bottom)
		)
	)
	(label "LPDDR5_DIE.DMI1"
		(at 199.39 194.31 0)
		(effects
			(font
				(size 1.27 1.27)
			)
			(justify left bottom)
		)
	)
	(label "LPDDR5_DIE.DQ0"
		(at 200.66 53.34 0)
		(effects
			(font
				(size 1.27 1.27)
			)
			(justify left bottom)
		)
	)
	(label "LPDDR5_DIE.DMI1"
		(at 234.95 76.2 0)
		(effects
			(font
				(size 1.27 1.27)
			)
			(justify left bottom)
		)
	)
	(label "LPDDR5_DIE.DQ14"
		(at 200.66 132.08 0)
		(effects
			(font
				(size 1.27 1.27)
			)
			(justify left bottom)
		)
	)
	(label "LPDDR5_DIE.WCK1_P"
		(at 234.95 162.56 0)
		(effects
			(font
				(size 1.27 1.27)
			)
			(justify left bottom)
		)
	)
	(label "LPDDR5_DIE.CS0"
		(at 200.66 87.63 0)
		(effects
			(font
				(size 1.27 1.27)
			)
			(justify left bottom)
		)
	)
	(label "LPDDR5_OUT.DQ1"
		(at 153.67 199.39 0)
		(effects
			(font
				(size 1.27 1.27)
			)
			(justify left bottom)
		)
	)
	(label "LPDDR5_DIE.WCK0_N"
		(at 200.66 146.05 0)
		(effects
			(font
				(size 1.27 1.27)
			)
			(justify left bottom)
		)
	)
	(label "LPDDR5_DIE.DQ4"
		(at 200.66 62.23 0)
		(effects
			(font
				(size 1.27 1.27)
			)
			(justify left bottom)
		)
	)
	(label "LPDDR5_DIE.CS1"
		(at 200.66 90.17 0)
		(effects
			(font
				(size 1.27 1.27)
			)
			(justify left bottom)
		)
	)
	(label "LPDDR5_DIE.DMI0"
		(at 200.66 191.77 0)
		(effects
			(font
				(size 1.27 1.27)
			)
			(justify left bottom)
		)
	)
	(label "LPDDR5_OUT.DMI0"
		(at 153.67 191.77 0)
		(effects
			(font
				(size 1.27 1.27)
			)
			(justify left bottom)
		)
	)
	(label "LPDDR5_DIE.DQ8"
		(at 234.95 115.57 0)
		(effects
			(font
				(size 1.27 1.27)
			)
			(justify left bottom)
		)
	)
	(label "LPDDR5_DIE.DQ10"
		(at 234.95 118.11 0)
		(effects
			(font
				(size 1.27 1.27)
			)
			(justify left bottom)
		)
	)
	(label "LPDDR5_DIE.DQ2"
		(at 234.95 50.8 0)
		(effects
			(font
				(size 1.27 1.27)
			)
			(justify left bottom)
		)
	)
	(label "LPDDR5_DIE.WCK1_P"
		(at 200.66 162.56 0)
		(effects
			(font
				(size 1.27 1.27)
			)
			(justify left bottom)
		)
	)
	(label "LPDDR5_OUT.DQ11"
		(at 153.67 232.41 0)
		(effects
			(font
				(size 1.27 1.27)
			)
			(justify left bottom)
		)
	)
	(hierarchical_label "LPDDR5_DIE{LPDDR5}"
		(shape output)
		(at 327.66 20.32 0)
		(effects
			(font
				(size 1.27 1.27)
			)
			(justify left)
		)
	)
	(hierarchical_label "LPDDR5_DIE{LPDDR5}"
		(shape output)
		(at 327.66 186.69 0)
		(effects
			(font
				(size 1.27 1.27)
			)
			(justify left)
		)
	)
	(hierarchical_label "LPDDR5_OUT{LPDDR5}"
		(shape output)
		(at 128.27 267.97 180)
		(effects
			(font
				(size 1.27 1.27)
			)
			(justify right)
		)
	)
	(hierarchical_label "LPDDR5_IN{LPDDR5}"
		(shape input)
		(at 127 27.94 180)
		(effects
			(font
				(size 1.27 1.27)
			)
			(justify right)
		)
	)
	(symbol
		(lib_id "antmicroResistors0402:R_100R_0402")
		(at 262.89 78.74 0)
		(unit 1)
		(exclude_from_sim no)
		(in_bom yes)
		(on_board yes)
		(dnp no)
		(property "Reference" "R86"
			(at 267.97 77.47 0)
			(effects
				(font
					(size 1.27 1.27)
					(thickness 0.15)
				)
				(justify left)
			)
		)
		(property "Value" "R_100R_0402"
			(at 283.21 91.44 0)
			(effects
				(font
					(size 1.27 1.27)
					(thickness 0.15)
				)
				(justify left bottom)
				(hide yes)
			)
		)
		(property "Footprint" "antmicro-footprints:R_0402_1005Metric"
			(at 283.21 93.98 0)
			(effects
				(font
					(size 1.27 1.27)
					(thickness 0.15)
				)
				(justify left bottom)
				(hide yes)
			)
		)
		(property "Datasheet" "https://www.bourns.com/docs/product-datasheets/cr.pdf"
			(at 283.21 96.52 0)
			(effects
				(font
					(size 1.27 1.27)
					(thickness 0.15)
				)
				(justify left bottom)
				(hide yes)
			)
		)
		(property "Description" ""
			(at 262.89 78.74 0)
			(effects
				(font
					(size 1.27 1.27)
				)
			)
		)
		(property "MPN" "CR0402-FX-1000GLF"
			(at 283.21 99.06 0)
			(effects
				(font
					(size 1.27 1.27)
					(thickness 0.15)
				)
				(justify left bottom)
				(hide yes)
			)
		)
		(property "Manufacturer" "Bourns"
			(at 283.21 101.6 0)
			(effects
				(font
					(size 1.27 1.27)
					(thickness 0.15)
				)
				(justify left bottom)
				(hide yes)
			)
		)
		(property "License" "Apache-2.0"
			(at 283.21 104.14 0)
			(effects
				(font
					(size 1.27 1.27)
					(thickness 0.15)
				)
				(justify left bottom)
				(hide yes)
			)
		)
		(property "Author" "Antmicro"
			(at 283.21 106.68 0)
			(effects
				(font
					(size 1.27 1.27)
					(thickness 0.15)
				)
				(justify left bottom)
				(hide yes)
			)
		)
		(property "Val" "100R"
			(at 260.35 77.47 0)
			(effects
				(font
					(size 1.27 1.27)
					(thickness 0.15)
				)
			)
		)
		(property "Tolerance" "1%"
			(at 283.21 88.9 0)
			(effects
				(font
					(size 1.27 1.27)
				)
				(justify left bottom)
				(hide yes)
			)
		)
		(pin "1"
		)
		(pin "2"
		)
		(instances
			(project ""
				(path ""
					(reference "R92")
					(unit 1)
				)
				(path ""
					(reference "R86")
					(unit 1)
				)
			)
		)
	)
	(symbol
		(lib_id "antmicroResistors0402:R_100R_0402")
		(at 181.61 160.02 0)
		(unit 1)
		(exclude_from_sim no)
		(in_bom yes)
		(on_board yes)
		(dnp no)
		(property "Reference" "R13"
			(at 186.69 158.75 0)
			(effects
				(font
					(size 1.27 1.27)
					(thickness 0.15)
				)
				(justify left)
			)
		)
		(property "Value" "R_100R_0402"
			(at 201.93 172.72 0)
			(effects
				(font
					(size 1.27 1.27)
					(thickness 0.15)
				)
				(justify left bottom)
				(hide yes)
			)
		)
		(property "Footprint" "antmicro-footprints:R_0402_1005Metric"
			(at 201.93 175.26 0)
			(effects
				(font
					(size 1.27 1.27)
					(thickness 0.15)
				)
				(justify left bottom)
				(hide yes)
			)
		)
		(property "Datasheet" "https://www.bourns.com/docs/product-datasheets/cr.pdf"
			(at 201.93 177.8 0)
			(effects
				(font
					(size 1.27 1.27)
					(thickness 0.15)
				)
				(justify left bottom)
				(hide yes)
			)
		)
		(property "Description" ""
			(at 181.61 160.02 0)
			(effects
				(font
					(size 1.27 1.27)
				)
			)
		)
		(property "MPN" "CR0402-FX-1000GLF"
			(at 201.93 180.34 0)
			(effects
				(font
					(size 1.27 1.27)
					(thickness 0.15)
				)
				(justify left bottom)
				(hide yes)
			)
		)
		(property "Manufacturer" "Bourns"
			(at 201.93 182.88 0)
			(effects
				(font
					(size 1.27 1.27)
					(thickness 0.15)
				)
				(justify left bottom)
				(hide yes)
			)
		)
		(property "License" "Apache-2.0"
			(at 201.93 185.42 0)
			(effects
				(font
					(size 1.27 1.27)
					(thickness 0.15)
				)
				(justify left bottom)
				(hide yes)
			)
		)
		(property "Author" "Antmicro"
			(at 201.93 187.96 0)
			(effects
				(font
					(size 1.27 1.27)
					(thickness 0.15)
				)
				(justify left bottom)
				(hide yes)
			)
		)
		(property "Val" "100R"
			(at 179.07 158.75 0)
			(effects
				(font
					(size 1.27 1.27)
					(thickness 0.15)
				)
			)
		)
		(property "Tolerance" "1%"
			(at 201.93 170.18 0)
			(effects
				(font
					(size 1.27 1.27)
				)
				(justify left bottom)
				(hide yes)
			)
		)
		(pin "1"
		)
		(pin "2"
		)
		(instances
			(project ""
				(path ""
					(reference "R66")
					(unit 1)
				)
				(path ""
					(reference "R13")
					(unit 1)
				)
			)
		)
	)
	(symbol
		(lib_id "antmicroResistors0402:R_100R_0402")
		(at 262.89 81.28 0)
		(unit 1)
		(exclude_from_sim no)
		(in_bom yes)
		(on_board yes)
		(dnp no)
		(property "Reference" "R94"
			(at 267.97 80.01 0)
			(effects
				(font
					(size 1.27 1.27)
					(thickness 0.15)
				)
				(justify left)
			)
		)
		(property "Value" "R_100R_0402"
			(at 283.21 93.98 0)
			(effects
				(font
					(size 1.27 1.27)
					(thickness 0.15)
				)
				(justify left bottom)
				(hide yes)
			)
		)
		(property "Footprint" "antmicro-footprints:R_0402_1005Metric"
			(at 283.21 96.52 0)
			(effects
				(font
					(size 1.27 1.27)
					(thickness 0.15)
				)
				(justify left bottom)
				(hide yes)
			)
		)
		(property "Datasheet" "https://www.bourns.com/docs/product-datasheets/cr.pdf"
			(at 283.21 99.06 0)
			(effects
				(font
					(size 1.27 1.27)
					(thickness 0.15)
				)
				(justify left bottom)
				(hide yes)
			)
		)
		(property "Description" ""
			(at 262.89 81.28 0)
			(effects
				(font
					(size 1.27 1.27)
				)
			)
		)
		(property "MPN" "CR0402-FX-1000GLF"
			(at 283.21 101.6 0)
			(effects
				(font
					(size 1.27 1.27)
					(thickness 0.15)
				)
				(justify left bottom)
				(hide yes)
			)
		)
		(property "Manufacturer" "Bourns"
			(at 283.21 104.14 0)
			(effects
				(font
					(size 1.27 1.27)
					(thickness 0.15)
				)
				(justify left bottom)
				(hide yes)
			)
		)
		(property "License" "Apache-2.0"
			(at 283.21 106.68 0)
			(effects
				(font
					(size 1.27 1.27)
					(thickness 0.15)
				)
				(justify left bottom)
				(hide yes)
			)
		)
		(property "Author" "Antmicro"
			(at 283.21 109.22 0)
			(effects
				(font
					(size 1.27 1.27)
					(thickness 0.15)
				)
				(justify left bottom)
				(hide yes)
			)
		)
		(property "Val" "100R"
			(at 260.35 80.01 0)
			(effects
				(font
					(size 1.27 1.27)
					(thickness 0.15)
				)
			)
		)
		(property "Tolerance" "1%"
			(at 283.21 91.44 0)
			(effects
				(font
					(size 1.27 1.27)
				)
				(justify left bottom)
				(hide yes)
			)
		)
		(pin "1"
		)
		(pin "2"
		)
		(instances
			(project ""
				(path ""
					(reference "R96")
					(unit 1)
				)
				(path ""
					(reference "R94")
					(unit 1)
				)
			)
		)
	)
	(symbol
		(lib_id "antmicroResistors0402:R_100R_0402")
		(at 262.89 146.05 0)
		(unit 1)
		(exclude_from_sim no)
		(in_bom yes)
		(on_board yes)
		(dnp no)
		(property "Reference" "R25"
			(at 267.97 144.78 0)
			(effects
				(font
					(size 1.27 1.27)
					(thickness 0.15)
				)
				(justify left)
			)
		)
		(property "Value" "R_100R_0402"
			(at 283.21 158.75 0)
			(effects
				(font
					(size 1.27 1.27)
					(thickness 0.15)
				)
				(justify left bottom)
				(hide yes)
			)
		)
		(property "Footprint" "antmicro-footprints:R_0402_1005Metric"
			(at 283.21 161.29 0)
			(effects
				(font
					(size 1.27 1.27)
					(thickness 0.15)
				)
				(justify left bottom)
				(hide yes)
			)
		)
		(property "Datasheet" "https://www.bourns.com/docs/product-datasheets/cr.pdf"
			(at 283.21 163.83 0)
			(effects
				(font
					(size 1.27 1.27)
					(thickness 0.15)
				)
				(justify left bottom)
				(hide yes)
			)
		)
		(property "Description" ""
			(at 262.89 146.05 0)
			(effects
				(font
					(size 1.27 1.27)
				)
			)
		)
		(property "MPN" "CR0402-FX-1000GLF"
			(at 283.21 166.37 0)
			(effects
				(font
					(size 1.27 1.27)
					(thickness 0.15)
				)
				(justify left bottom)
				(hide yes)
			)
		)
		(property "Manufacturer" "Bourns"
			(at 283.21 168.91 0)
			(effects
				(font
					(size 1.27 1.27)
					(thickness 0.15)
				)
				(justify left bottom)
				(hide yes)
			)
		)
		(property "License" "Apache-2.0"
			(at 283.21 171.45 0)
			(effects
				(font
					(size 1.27 1.27)
					(thickness 0.15)
				)
				(justify left bottom)
				(hide yes)
			)
		)
		(property "Author" "Antmicro"
			(at 283.21 173.99 0)
			(effects
				(font
					(size 1.27 1.27)
					(thickness 0.15)
				)
				(justify left bottom)
				(hide yes)
			)
		)
		(property "Val" "100R"
			(at 260.35 144.78 0)
			(effects
				(font
					(size 1.27 1.27)
					(thickness 0.15)
				)
			)
		)
		(property "Tolerance" "1%"
			(at 283.21 156.21 0)
			(effects
				(font
					(size 1.27 1.27)
				)
				(justify left bottom)
				(hide yes)
			)
		)
		(pin "1"
		)
		(pin "2"
		)
		(instances
			(project ""
				(path ""
					(reference "R79")
					(unit 1)
				)
				(path ""
					(reference "R25")
					(unit 1)
				)
			)
		)
	)
	(symbol
		(lib_id "antmicroResistorNetworksArrays:R_4x100R_0402_array")
		(at 260.35 115.57 0)
		(unit 1)
		(exclude_from_sim no)
		(in_bom yes)
		(on_board yes)
		(dnp no)
		(property "Reference" "R23"
			(at 262.89 113.03 0)
			(effects
				(font
					(size 1.27 1.27)
					(thickness 0.15)
				)
			)
		)
		(property "Value" "R_4x100R_0402_array"
			(at 287.02 120.65 0)
			(effects
				(font
					(size 1.27 1.27)
					(thickness 0.15)
				)
				(justify left bottom)
				(hide yes)
			)
		)
		(property "Footprint" "antmicro-footprints:R_Array_4x0402_Panasonic_EXB28V"
			(at 287.02 125.73 0)
			(effects
				(font
					(size 1.27 1.27)
					(thickness 0.15)
				)
				(justify left bottom)
				(hide yes)
			)
		)
		(property "Datasheet" "http://industrial.panasonic.com/cdbs/www-data/pdf/AOC0000/AOC0000C14.pdf"
			(at 287.02 128.27 0)
			(effects
				(font
					(size 1.27 1.27)
					(thickness 0.15)
				)
				(justify left bottom)
				(hide yes)
			)
		)
		(property "Description" ""
			(at 260.35 115.57 0)
			(effects
				(font
					(size 1.27 1.27)
				)
			)
		)
		(property "MPN" "EXB-28V101JX"
			(at 287.02 130.81 0)
			(effects
				(font
					(size 1.27 1.27)
					(thickness 0.15)
				)
				(justify left bottom)
				(hide yes)
			)
		)
		(property "Manufacturer" "Panasonic"
			(at 287.02 133.35 0)
			(effects
				(font
					(size 1.27 1.27)
					(thickness 0.15)
				)
				(justify left bottom)
				(hide yes)
			)
		)
		(property "Author" "Antmicro"
			(at 287.02 135.89 0)
			(effects
				(font
					(size 1.27 1.27)
					(thickness 0.15)
				)
				(justify left bottom)
				(hide yes)
			)
		)
		(property "License" "Apache-2.0"
			(at 287.02 138.43 0)
			(effects
				(font
					(size 1.27 1.27)
					(thickness 0.15)
				)
				(justify left bottom)
				(hide yes)
			)
		)
		(property "Val" "R_4x100R_0402"
			(at 274.32 113.03 0)
			(effects
				(font
					(size 1.27 1.27)
				)
			)
		)
		(pin "1"
		)
		(pin "2"
		)
		(pin "3"
		)
		(pin "4"
		)
		(pin "5"
		)
		(pin "6"
		)
		(pin "7"
		)
		(pin "8"
		)
		(instances
			(project ""
				(path ""
					(reference "R77")
					(unit 1)
				)
				(path ""
					(reference "R23")
					(unit 1)
				)
			)
		)
	)
	(symbol
		(lib_id "antmicroResistors0402:R_100R_0402")
		(at 181.61 173.99 0)
		(unit 1)
		(exclude_from_sim no)
		(in_bom yes)
		(on_board yes)
		(dnp no)
		(property "Reference" "R15"
			(at 186.69 172.72 0)
			(effects
				(font
					(size 1.27 1.27)
					(thickness 0.15)
				)
				(justify left)
			)
		)
		(property "Value" "R_100R_0402"
			(at 201.93 186.69 0)
			(effects
				(font
					(size 1.27 1.27)
					(thickness 0.15)
				)
				(justify left bottom)
				(hide yes)
			)
		)
		(property "Footprint" "antmicro-footprints:R_0402_1005Metric"
			(at 201.93 189.23 0)
			(effects
				(font
					(size 1.27 1.27)
					(thickness 0.15)
				)
				(justify left bottom)
				(hide yes)
			)
		)
		(property "Datasheet" "https://www.bourns.com/docs/product-datasheets/cr.pdf"
			(at 201.93 191.77 0)
			(effects
				(font
					(size 1.27 1.27)
					(thickness 0.15)
				)
				(justify left bottom)
				(hide yes)
			)
		)
		(property "Description" ""
			(at 181.61 173.99 0)
			(effects
				(font
					(size 1.27 1.27)
				)
			)
		)
		(property "MPN" "CR0402-FX-1000GLF"
			(at 201.93 194.31 0)
			(effects
				(font
					(size 1.27 1.27)
					(thickness 0.15)
				)
				(justify left bottom)
				(hide yes)
			)
		)
		(property "Manufacturer" "Bourns"
			(at 201.93 196.85 0)
			(effects
				(font
					(size 1.27 1.27)
					(thickness 0.15)
				)
				(justify left bottom)
				(hide yes)
			)
		)
		(property "License" "Apache-2.0"
			(at 201.93 199.39 0)
			(effects
				(font
					(size 1.27 1.27)
					(thickness 0.15)
				)
				(justify left bottom)
				(hide yes)
			)
		)
		(property "Author" "Antmicro"
			(at 201.93 201.93 0)
			(effects
				(font
					(size 1.27 1.27)
					(thickness 0.15)
				)
				(justify left bottom)
				(hide yes)
			)
		)
		(property "Val" "100R"
			(at 179.07 172.72 0)
			(effects
				(font
					(size 1.27 1.27)
					(thickness 0.15)
				)
			)
		)
		(property "Tolerance" "1%"
			(at 201.93 184.15 0)
			(effects
				(font
					(size 1.27 1.27)
				)
				(justify left bottom)
				(hide yes)
			)
		)
		(pin "1"
		)
		(pin "2"
		)
		(instances
			(project ""
				(path ""
					(reference "R68")
					(unit 1)
				)
				(path ""
					(reference "R15")
					(unit 1)
				)
			)
		)
	)
	(symbol
		(lib_id "antmicroResistors0402:R_100R_0402")
		(at 262.89 176.53 0)
		(unit 1)
		(exclude_from_sim no)
		(in_bom yes)
		(on_board yes)
		(dnp no)
		(property "Reference" "R55"
			(at 267.97 175.26 0)
			(effects
				(font
					(size 1.27 1.27)
					(thickness 0.15)
				)
				(justify left)
			)
		)
		(property "Value" "R_100R_0402"
			(at 283.21 189.23 0)
			(effects
				(font
					(size 1.27 1.27)
					(thickness 0.15)
				)
				(justify left bottom)
				(hide yes)
			)
		)
		(property "Footprint" "antmicro-footprints:R_0402_1005Metric"
			(at 283.21 191.77 0)
			(effects
				(font
					(size 1.27 1.27)
					(thickness 0.15)
				)
				(justify left bottom)
				(hide yes)
			)
		)
		(property "Datasheet" "https://www.bourns.com/docs/product-datasheets/cr.pdf"
			(at 283.21 194.31 0)
			(effects
				(font
					(size 1.27 1.27)
					(thickness 0.15)
				)
				(justify left bottom)
				(hide yes)
			)
		)
		(property "Description" ""
			(at 262.89 176.53 0)
			(effects
				(font
					(size 1.27 1.27)
				)
			)
		)
		(property "MPN" "CR0402-FX-1000GLF"
			(at 283.21 196.85 0)
			(effects
				(font
					(size 1.27 1.27)
					(thickness 0.15)
				)
				(justify left bottom)
				(hide yes)
			)
		)
		(property "Manufacturer" "Bourns"
			(at 283.21 199.39 0)
			(effects
				(font
					(size 1.27 1.27)
					(thickness 0.15)
				)
				(justify left bottom)
				(hide yes)
			)
		)
		(property "License" "Apache-2.0"
			(at 283.21 201.93 0)
			(effects
				(font
					(size 1.27 1.27)
					(thickness 0.15)
				)
				(justify left bottom)
				(hide yes)
			)
		)
		(property "Author" "Antmicro"
			(at 283.21 204.47 0)
			(effects
				(font
					(size 1.27 1.27)
					(thickness 0.15)
				)
				(justify left bottom)
				(hide yes)
			)
		)
		(property "Val" "100R"
			(at 260.35 175.26 0)
			(effects
				(font
					(size 1.27 1.27)
					(thickness 0.15)
				)
			)
		)
		(property "Tolerance" "1%"
			(at 283.21 186.69 0)
			(effects
				(font
					(size 1.27 1.27)
				)
				(justify left bottom)
				(hide yes)
			)
		)
		(pin "1"
		)
		(pin "2"
		)
		(instances
			(project ""
				(path ""
					(reference "R84")
					(unit 1)
				)
				(path ""
					(reference "R55")
					(unit 1)
				)
			)
		)
	)
	(symbol
		(lib_id "antmicroResistors0402:R_100R_0402")
		(at 262.89 160.02 0)
		(unit 1)
		(exclude_from_sim no)
		(in_bom yes)
		(on_board yes)
		(dnp no)
		(property "Reference" "R49"
			(at 267.97 158.75 0)
			(effects
				(font
					(size 1.27 1.27)
					(thickness 0.15)
				)
				(justify left)
			)
		)
		(property "Value" "R_100R_0402"
			(at 283.21 172.72 0)
			(effects
				(font
					(size 1.27 1.27)
					(thickness 0.15)
				)
				(justify left bottom)
				(hide yes)
			)
		)
		(property "Footprint" "antmicro-footprints:R_0402_1005Metric"
			(at 283.21 175.26 0)
			(effects
				(font
					(size 1.27 1.27)
					(thickness 0.15)
				)
				(justify left bottom)
				(hide yes)
			)
		)
		(property "Datasheet" "https://www.bourns.com/docs/product-datasheets/cr.pdf"
			(at 283.21 177.8 0)
			(effects
				(font
					(size 1.27 1.27)
					(thickness 0.15)
				)
				(justify left bottom)
				(hide yes)
			)
		)
		(property "Description" ""
			(at 262.89 160.02 0)
			(effects
				(font
					(size 1.27 1.27)
				)
			)
		)
		(property "MPN" "CR0402-FX-1000GLF"
			(at 283.21 180.34 0)
			(effects
				(font
					(size 1.27 1.27)
					(thickness 0.15)
				)
				(justify left bottom)
				(hide yes)
			)
		)
		(property "Manufacturer" "Bourns"
			(at 283.21 182.88 0)
			(effects
				(font
					(size 1.27 1.27)
					(thickness 0.15)
				)
				(justify left bottom)
				(hide yes)
			)
		)
		(property "License" "Apache-2.0"
			(at 283.21 185.42 0)
			(effects
				(font
					(size 1.27 1.27)
					(thickness 0.15)
				)
				(justify left bottom)
				(hide yes)
			)
		)
		(property "Author" "Antmicro"
			(at 283.21 187.96 0)
			(effects
				(font
					(size 1.27 1.27)
					(thickness 0.15)
				)
				(justify left bottom)
				(hide yes)
			)
		)
		(property "Val" "100R"
			(at 260.35 158.75 0)
			(effects
				(font
					(size 1.27 1.27)
					(thickness 0.15)
				)
			)
		)
		(property "Tolerance" "1%"
			(at 283.21 170.18 0)
			(effects
				(font
					(size 1.27 1.27)
				)
				(justify left bottom)
				(hide yes)
			)
		)
		(pin "1"
		)
		(pin "2"
		)
		(instances
			(project ""
				(path ""
					(reference "R81")
					(unit 1)
				)
				(path ""
					(reference "R49")
					(unit 1)
				)
			)
		)
	)
	(symbol
		(lib_id "antmicroResistors0402:R_100R_0402")
		(at 262.89 162.56 0)
		(unit 1)
		(exclude_from_sim no)
		(in_bom yes)
		(on_board yes)
		(dnp no)
		(property "Reference" "R53"
			(at 267.97 161.29 0)
			(effects
				(font
					(size 1.27 1.27)
					(thickness 0.15)
				)
				(justify left)
			)
		)
		(property "Value" "R_100R_0402"
			(at 283.21 175.26 0)
			(effects
				(font
					(size 1.27 1.27)
					(thickness 0.15)
				)
				(justify left bottom)
				(hide yes)
			)
		)
		(property "Footprint" "antmicro-footprints:R_0402_1005Metric"
			(at 283.21 177.8 0)
			(effects
				(font
					(size 1.27 1.27)
					(thickness 0.15)
				)
				(justify left bottom)
				(hide yes)
			)
		)
		(property "Datasheet" "https://www.bourns.com/docs/product-datasheets/cr.pdf"
			(at 283.21 180.34 0)
			(effects
				(font
					(size 1.27 1.27)
					(thickness 0.15)
				)
				(justify left bottom)
				(hide yes)
			)
		)
		(property "Description" ""
			(at 262.89 162.56 0)
			(effects
				(font
					(size 1.27 1.27)
				)
			)
		)
		(property "MPN" "CR0402-FX-1000GLF"
			(at 283.21 182.88 0)
			(effects
				(font
					(size 1.27 1.27)
					(thickness 0.15)
				)
				(justify left bottom)
				(hide yes)
			)
		)
		(property "Manufacturer" "Bourns"
			(at 283.21 185.42 0)
			(effects
				(font
					(size 1.27 1.27)
					(thickness 0.15)
				)
				(justify left bottom)
				(hide yes)
			)
		)
		(property "License" "Apache-2.0"
			(at 283.21 187.96 0)
			(effects
				(font
					(size 1.27 1.27)
					(thickness 0.15)
				)
				(justify left bottom)
				(hide yes)
			)
		)
		(property "Author" "Antmicro"
			(at 283.21 190.5 0)
			(effects
				(font
					(size 1.27 1.27)
					(thickness 0.15)
				)
				(justify left bottom)
				(hide yes)
			)
		)
		(property "Val" "100R"
			(at 260.35 161.29 0)
			(effects
				(font
					(size 1.27 1.27)
					(thickness 0.15)
				)
			)
		)
		(property "Tolerance" "1%"
			(at 283.21 172.72 0)
			(effects
				(font
					(size 1.27 1.27)
				)
				(justify left bottom)
				(hide yes)
			)
		)
		(pin "1"
		)
		(pin "2"
		)
		(instances
			(project ""
				(path ""
					(reference "R82")
					(unit 1)
				)
				(path ""
					(reference "R53")
					(unit 1)
				)
			)
		)
	)
	(symbol
		(lib_id "antmicroResistors0402:R_100R_0402")
		(at 262.89 148.59 0)
		(unit 1)
		(exclude_from_sim no)
		(in_bom yes)
		(on_board yes)
		(dnp no)
		(property "Reference" "R48"
			(at 267.97 147.32 0)
			(effects
				(font
					(size 1.27 1.27)
					(thickness 0.15)
				)
				(justify left)
			)
		)
		(property "Value" "R_100R_0402"
			(at 283.21 161.29 0)
			(effects
				(font
					(size 1.27 1.27)
					(thickness 0.15)
				)
				(justify left bottom)
				(hide yes)
			)
		)
		(property "Footprint" "antmicro-footprints:R_0402_1005Metric"
			(at 283.21 163.83 0)
			(effects
				(font
					(size 1.27 1.27)
					(thickness 0.15)
				)
				(justify left bottom)
				(hide yes)
			)
		)
		(property "Datasheet" "https://www.bourns.com/docs/product-datasheets/cr.pdf"
			(at 283.21 166.37 0)
			(effects
				(font
					(size 1.27 1.27)
					(thickness 0.15)
				)
				(justify left bottom)
				(hide yes)
			)
		)
		(property "Description" ""
			(at 262.89 148.59 0)
			(effects
				(font
					(size 1.27 1.27)
				)
			)
		)
		(property "MPN" "CR0402-FX-1000GLF"
			(at 283.21 168.91 0)
			(effects
				(font
					(size 1.27 1.27)
					(thickness 0.15)
				)
				(justify left bottom)
				(hide yes)
			)
		)
		(property "Manufacturer" "Bourns"
			(at 283.21 171.45 0)
			(effects
				(font
					(size 1.27 1.27)
					(thickness 0.15)
				)
				(justify left bottom)
				(hide yes)
			)
		)
		(property "License" "Apache-2.0"
			(at 283.21 173.99 0)
			(effects
				(font
					(size 1.27 1.27)
					(thickness 0.15)
				)
				(justify left bottom)
				(hide yes)
			)
		)
		(property "Author" "Antmicro"
			(at 283.21 176.53 0)
			(effects
				(font
					(size 1.27 1.27)
					(thickness 0.15)
				)
				(justify left bottom)
				(hide yes)
			)
		)
		(property "Val" "100R"
			(at 260.35 147.32 0)
			(effects
				(font
					(size 1.27 1.27)
					(thickness 0.15)
				)
			)
		)
		(property "Tolerance" "1%"
			(at 283.21 158.75 0)
			(effects
				(font
					(size 1.27 1.27)
				)
				(justify left bottom)
				(hide yes)
			)
		)
		(pin "1"
		)
		(pin "2"
		)
		(instances
			(project ""
				(path ""
					(reference "R80")
					(unit 1)
				)
				(path ""
					(reference "R48")
					(unit 1)
				)
			)
		)
	)
	(symbol
		(lib_id "antmicroResistorNetworksArrays:R_4x100R_0402_array")
		(at 260.35 45.72 0)
		(unit 1)
		(exclude_from_sim no)
		(in_bom yes)
		(on_board yes)
		(dnp no)
		(property "Reference" "R18"
			(at 262.89 43.18 0)
			(effects
				(font
					(size 1.27 1.27)
					(thickness 0.15)
				)
			)
		)
		(property "Value" "R_4x100R_0402_array"
			(at 287.02 50.8 0)
			(effects
				(font
					(size 1.27 1.27)
					(thickness 0.15)
				)
				(justify left bottom)
				(hide yes)
			)
		)
		(property "Footprint" "antmicro-footprints:R_Array_4x0402_Panasonic_EXB28V"
			(at 287.02 55.88 0)
			(effects
				(font
					(size 1.27 1.27)
					(thickness 0.15)
				)
				(justify left bottom)
				(hide yes)
			)
		)
		(property "Datasheet" "http://industrial.panasonic.com/cdbs/www-data/pdf/AOC0000/AOC0000C14.pdf"
			(at 287.02 58.42 0)
			(effects
				(font
					(size 1.27 1.27)
					(thickness 0.15)
				)
				(justify left bottom)
				(hide yes)
			)
		)
		(property "Description" ""
			(at 260.35 45.72 0)
			(effects
				(font
					(size 1.27 1.27)
				)
			)
		)
		(property "MPN" "EXB-28V101JX"
			(at 287.02 60.96 0)
			(effects
				(font
					(size 1.27 1.27)
					(thickness 0.15)
				)
				(justify left bottom)
				(hide yes)
			)
		)
		(property "Manufacturer" "Panasonic"
			(at 287.02 63.5 0)
			(effects
				(font
					(size 1.27 1.27)
					(thickness 0.15)
				)
				(justify left bottom)
				(hide yes)
			)
		)
		(property "Author" "Antmicro"
			(at 287.02 66.04 0)
			(effects
				(font
					(size 1.27 1.27)
					(thickness 0.15)
				)
				(justify left bottom)
				(hide yes)
			)
		)
		(property "License" "Apache-2.0"
			(at 287.02 68.58 0)
			(effects
				(font
					(size 1.27 1.27)
					(thickness 0.15)
				)
				(justify left bottom)
				(hide yes)
			)
		)
		(property "Val" "R_4x100R_0402"
			(at 274.32 43.18 0)
			(effects
				(font
					(size 1.27 1.27)
				)
			)
		)
		(pin "1"
		)
		(pin "2"
		)
		(pin "3"
		)
		(pin "4"
		)
		(pin "5"
		)
		(pin "6"
		)
		(pin "7"
		)
		(pin "8"
		)
		(instances
			(project ""
				(path ""
					(reference "R72")
					(unit 1)
				)
				(path ""
					(reference "R18")
					(unit 1)
				)
			)
		)
	)
	(symbol
		(lib_id "antmicroResistors0402:R_100R_0402")
		(at 181.61 148.59 0)
		(unit 1)
		(exclude_from_sim no)
		(in_bom yes)
		(on_board yes)
		(dnp no)
		(property "Reference" "R12"
			(at 186.69 147.32 0)
			(effects
				(font
					(size 1.27 1.27)
					(thickness 0.15)
				)
				(justify left)
			)
		)
		(property "Value" "R_100R_0402"
			(at 201.93 161.29 0)
			(effects
				(font
					(size 1.27 1.27)
					(thickness 0.15)
				)
				(justify left bottom)
				(hide yes)
			)
		)
		(property "Footprint" "antmicro-footprints:R_0402_1005Metric"
			(at 201.93 163.83 0)
			(effects
				(font
					(size 1.27 1.27)
					(thickness 0.15)
				)
				(justify left bottom)
				(hide yes)
			)
		)
		(property "Datasheet" "https://www.bourns.com/docs/product-datasheets/cr.pdf"
			(at 201.93 166.37 0)
			(effects
				(font
					(size 1.27 1.27)
					(thickness 0.15)
				)
				(justify left bottom)
				(hide yes)
			)
		)
		(property "Description" ""
			(at 181.61 148.59 0)
			(effects
				(font
					(size 1.27 1.27)
				)
			)
		)
		(property "MPN" "CR0402-FX-1000GLF"
			(at 201.93 168.91 0)
			(effects
				(font
					(size 1.27 1.27)
					(thickness 0.15)
				)
				(justify left bottom)
				(hide yes)
			)
		)
		(property "Manufacturer" "Bourns"
			(at 201.93 171.45 0)
			(effects
				(font
					(size 1.27 1.27)
					(thickness 0.15)
				)
				(justify left bottom)
				(hide yes)
			)
		)
		(property "License" "Apache-2.0"
			(at 201.93 173.99 0)
			(effects
				(font
					(size 1.27 1.27)
					(thickness 0.15)
				)
				(justify left bottom)
				(hide yes)
			)
		)
		(property "Author" "Antmicro"
			(at 201.93 176.53 0)
			(effects
				(font
					(size 1.27 1.27)
					(thickness 0.15)
				)
				(justify left bottom)
				(hide yes)
			)
		)
		(property "Val" "100R"
			(at 179.07 147.32 0)
			(effects
				(font
					(size 1.27 1.27)
					(thickness 0.15)
				)
			)
		)
		(property "Tolerance" "1%"
			(at 201.93 158.75 0)
			(effects
				(font
					(size 1.27 1.27)
				)
				(justify left bottom)
				(hide yes)
			)
		)
		(pin "1"
		)
		(pin "2"
		)
		(instances
			(project ""
				(path ""
					(reference "R65")
					(unit 1)
				)
				(path ""
					(reference "R12")
					(unit 1)
				)
			)
		)
	)
	(symbol
		(lib_id "antmicroResistorNetworksArrays:R_4x100R_0402_array")
		(at 260.35 129.54 0)
		(unit 1)
		(exclude_from_sim no)
		(in_bom yes)
		(on_board yes)
		(dnp no)
		(property "Reference" "R24"
			(at 262.89 127 0)
			(effects
				(font
					(size 1.27 1.27)
					(thickness 0.15)
				)
			)
		)
		(property "Value" "R_4x100R_0402_array"
			(at 287.02 134.62 0)
			(effects
				(font
					(size 1.27 1.27)
					(thickness 0.15)
				)
				(justify left bottom)
				(hide yes)
			)
		)
		(property "Footprint" "antmicro-footprints:R_Array_4x0402_Panasonic_EXB28V"
			(at 287.02 139.7 0)
			(effects
				(font
					(size 1.27 1.27)
					(thickness 0.15)
				)
				(justify left bottom)
				(hide yes)
			)
		)
		(property "Datasheet" "http://industrial.panasonic.com/cdbs/www-data/pdf/AOC0000/AOC0000C14.pdf"
			(at 287.02 142.24 0)
			(effects
				(font
					(size 1.27 1.27)
					(thickness 0.15)
				)
				(justify left bottom)
				(hide yes)
			)
		)
		(property "Description" ""
			(at 260.35 129.54 0)
			(effects
				(font
					(size 1.27 1.27)
				)
			)
		)
		(property "MPN" "EXB-28V101JX"
			(at 287.02 144.78 0)
			(effects
				(font
					(size 1.27 1.27)
					(thickness 0.15)
				)
				(justify left bottom)
				(hide yes)
			)
		)
		(property "Manufacturer" "Panasonic"
			(at 287.02 147.32 0)
			(effects
				(font
					(size 1.27 1.27)
					(thickness 0.15)
				)
				(justify left bottom)
				(hide yes)
			)
		)
		(property "Author" "Antmicro"
			(at 287.02 149.86 0)
			(effects
				(font
					(size 1.27 1.27)
					(thickness 0.15)
				)
				(justify left bottom)
				(hide yes)
			)
		)
		(property "License" "Apache-2.0"
			(at 287.02 152.4 0)
			(effects
				(font
					(size 1.27 1.27)
					(thickness 0.15)
				)
				(justify left bottom)
				(hide yes)
			)
		)
		(property "Val" "R_4x100R_0402"
			(at 274.32 127 0)
			(effects
				(font
					(size 1.27 1.27)
				)
			)
		)
		(pin "1"
		)
		(pin "2"
		)
		(pin "3"
		)
		(pin "4"
		)
		(pin "5"
		)
		(pin "6"
		)
		(pin "7"
		)
		(pin "8"
		)
		(instances
			(project ""
				(path ""
					(reference "R78")
					(unit 1)
				)
				(path ""
					(reference "R24")
					(unit 1)
				)
			)
		)
	)
	(symbol
		(lib_id "antmicroResistors0402:R_100R_0402")
		(at 181.61 162.56 0)
		(unit 1)
		(exclude_from_sim no)
		(in_bom yes)
		(on_board yes)
		(dnp no)
		(property "Reference" "R14"
			(at 186.69 161.29 0)
			(effects
				(font
					(size 1.27 1.27)
					(thickness 0.15)
				)
				(justify left)
			)
		)
		(property "Value" "R_100R_0402"
			(at 201.93 175.26 0)
			(effects
				(font
					(size 1.27 1.27)
					(thickness 0.15)
				)
				(justify left bottom)
				(hide yes)
			)
		)
		(property "Footprint" "antmicro-footprints:R_0402_1005Metric"
			(at 201.93 177.8 0)
			(effects
				(font
					(size 1.27 1.27)
					(thickness 0.15)
				)
				(justify left bottom)
				(hide yes)
			)
		)
		(property "Datasheet" "https://www.bourns.com/docs/product-datasheets/cr.pdf"
			(at 201.93 180.34 0)
			(effects
				(font
					(size 1.27 1.27)
					(thickness 0.15)
				)
				(justify left bottom)
				(hide yes)
			)
		)
		(property "Description" ""
			(at 181.61 162.56 0)
			(effects
				(font
					(size 1.27 1.27)
				)
			)
		)
		(property "MPN" "CR0402-FX-1000GLF"
			(at 201.93 182.88 0)
			(effects
				(font
					(size 1.27 1.27)
					(thickness 0.15)
				)
				(justify left bottom)
				(hide yes)
			)
		)
		(property "Manufacturer" "Bourns"
			(at 201.93 185.42 0)
			(effects
				(font
					(size 1.27 1.27)
					(thickness 0.15)
				)
				(justify left bottom)
				(hide yes)
			)
		)
		(property "License" "Apache-2.0"
			(at 201.93 187.96 0)
			(effects
				(font
					(size 1.27 1.27)
					(thickness 0.15)
				)
				(justify left bottom)
				(hide yes)
			)
		)
		(property "Author" "Antmicro"
			(at 201.93 190.5 0)
			(effects
				(font
					(size 1.27 1.27)
					(thickness 0.15)
				)
				(justify left bottom)
				(hide yes)
			)
		)
		(property "Val" "100R"
			(at 179.07 161.29 0)
			(effects
				(font
					(size 1.27 1.27)
					(thickness 0.15)
				)
			)
		)
		(property "Tolerance" "1%"
			(at 201.93 172.72 0)
			(effects
				(font
					(size 1.27 1.27)
				)
				(justify left bottom)
				(hide yes)
			)
		)
		(pin "1"
		)
		(pin "2"
		)
		(instances
			(project ""
				(path ""
					(reference "R67")
					(unit 1)
				)
				(path ""
					(reference "R14")
					(unit 1)
				)
			)
		)
	)
	(symbol
		(lib_id "antmicroResistors0402:R_100R_0402")
		(at 181.61 81.28 0)
		(unit 1)
		(exclude_from_sim no)
		(in_bom yes)
		(on_board yes)
		(dnp no)
		(property "Reference" "R93"
			(at 186.69 80.01 0)
			(effects
				(font
					(size 1.27 1.27)
					(thickness 0.15)
				)
				(justify left)
			)
		)
		(property "Value" "R_100R_0402"
			(at 201.93 93.98 0)
			(effects
				(font
					(size 1.27 1.27)
					(thickness 0.15)
				)
				(justify left bottom)
				(hide yes)
			)
		)
		(property "Footprint" "antmicro-footprints:R_0402_1005Metric"
			(at 201.93 96.52 0)
			(effects
				(font
					(size 1.27 1.27)
					(thickness 0.15)
				)
				(justify left bottom)
				(hide yes)
			)
		)
		(property "Datasheet" "https://www.bourns.com/docs/product-datasheets/cr.pdf"
			(at 201.93 99.06 0)
			(effects
				(font
					(size 1.27 1.27)
					(thickness 0.15)
				)
				(justify left bottom)
				(hide yes)
			)
		)
		(property "Description" ""
			(at 181.61 81.28 0)
			(effects
				(font
					(size 1.27 1.27)
				)
			)
		)
		(property "MPN" "CR0402-FX-1000GLF"
			(at 201.93 101.6 0)
			(effects
				(font
					(size 1.27 1.27)
					(thickness 0.15)
				)
				(justify left bottom)
				(hide yes)
			)
		)
		(property "Manufacturer" "Bourns"
			(at 201.93 104.14 0)
			(effects
				(font
					(size 1.27 1.27)
					(thickness 0.15)
				)
				(justify left bottom)
				(hide yes)
			)
		)
		(property "License" "Apache-2.0"
			(at 201.93 106.68 0)
			(effects
				(font
					(size 1.27 1.27)
					(thickness 0.15)
				)
				(justify left bottom)
				(hide yes)
			)
		)
		(property "Author" "Antmicro"
			(at 201.93 109.22 0)
			(effects
				(font
					(size 1.27 1.27)
					(thickness 0.15)
				)
				(justify left bottom)
				(hide yes)
			)
		)
		(property "Val" "100R"
			(at 179.07 80.01 0)
			(effects
				(font
					(size 1.27 1.27)
					(thickness 0.15)
				)
			)
		)
		(property "Tolerance" "1%"
			(at 201.93 91.44 0)
			(effects
				(font
					(size 1.27 1.27)
				)
				(justify left bottom)
				(hide yes)
			)
		)
		(pin "1"
		)
		(pin "2"
		)
		(instances
			(project ""
				(path ""
					(reference "R95")
					(unit 1)
				)
				(path ""
					(reference "R93")
					(unit 1)
				)
			)
		)
	)
	(symbol
		(lib_id "antmicroResistors0402:R_100R_0402")
		(at 181.61 176.53 0)
		(unit 1)
		(exclude_from_sim no)
		(in_bom yes)
		(on_board yes)
		(dnp no)
		(property "Reference" "R16"
			(at 186.69 175.26 0)
			(effects
				(font
					(size 1.27 1.27)
					(thickness 0.15)
				)
				(justify left)
			)
		)
		(property "Value" "R_100R_0402"
			(at 201.93 189.23 0)
			(effects
				(font
					(size 1.27 1.27)
					(thickness 0.15)
				)
				(justify left bottom)
				(hide yes)
			)
		)
		(property "Footprint" "antmicro-footprints:R_0402_1005Metric"
			(at 201.93 191.77 0)
			(effects
				(font
					(size 1.27 1.27)
					(thickness 0.15)
				)
				(justify left bottom)
				(hide yes)
			)
		)
		(property "Datasheet" "https://www.bourns.com/docs/product-datasheets/cr.pdf"
			(at 201.93 194.31 0)
			(effects
				(font
					(size 1.27 1.27)
					(thickness 0.15)
				)
				(justify left bottom)
				(hide yes)
			)
		)
		(property "Description" ""
			(at 181.61 176.53 0)
			(effects
				(font
					(size 1.27 1.27)
				)
			)
		)
		(property "MPN" "CR0402-FX-1000GLF"
			(at 201.93 196.85 0)
			(effects
				(font
					(size 1.27 1.27)
					(thickness 0.15)
				)
				(justify left bottom)
				(hide yes)
			)
		)
		(property "Manufacturer" "Bourns"
			(at 201.93 199.39 0)
			(effects
				(font
					(size 1.27 1.27)
					(thickness 0.15)
				)
				(justify left bottom)
				(hide yes)
			)
		)
		(property "License" "Apache-2.0"
			(at 201.93 201.93 0)
			(effects
				(font
					(size 1.27 1.27)
					(thickness 0.15)
				)
				(justify left bottom)
				(hide yes)
			)
		)
		(property "Author" "Antmicro"
			(at 201.93 204.47 0)
			(effects
				(font
					(size 1.27 1.27)
					(thickness 0.15)
				)
				(justify left bottom)
				(hide yes)
			)
		)
		(property "Val" "100R"
			(at 179.07 175.26 0)
			(effects
				(font
					(size 1.27 1.27)
					(thickness 0.15)
				)
			)
		)
		(property "Tolerance" "1%"
			(at 201.93 186.69 0)
			(effects
				(font
					(size 1.27 1.27)
				)
				(justify left bottom)
				(hide yes)
			)
		)
		(pin "1"
		)
		(pin "2"
		)
		(instances
			(project ""
				(path ""
					(reference "R70")
					(unit 1)
				)
				(path ""
					(reference "R16")
					(unit 1)
				)
			)
		)
	)
	(symbol
		(lib_id "antmicroResistorNetworksArrays:R_4x100R_0402_array")
		(at 260.35 87.63 0)
		(unit 1)
		(exclude_from_sim no)
		(in_bom yes)
		(on_board yes)
		(dnp no)
		(property "Reference" "R21"
			(at 262.89 85.09 0)
			(effects
				(font
					(size 1.27 1.27)
					(thickness 0.15)
				)
			)
		)
		(property "Value" "R_4x100R_0402_array"
			(at 287.02 92.71 0)
			(effects
				(font
					(size 1.27 1.27)
					(thickness 0.15)
				)
				(justify left bottom)
				(hide yes)
			)
		)
		(property "Footprint" "antmicro-footprints:R_Array_4x0402_Panasonic_EXB28V"
			(at 287.02 97.79 0)
			(effects
				(font
					(size 1.27 1.27)
					(thickness 0.15)
				)
				(justify left bottom)
				(hide yes)
			)
		)
		(property "Datasheet" "http://industrial.panasonic.com/cdbs/www-data/pdf/AOC0000/AOC0000C14.pdf"
			(at 287.02 100.33 0)
			(effects
				(font
					(size 1.27 1.27)
					(thickness 0.15)
				)
				(justify left bottom)
				(hide yes)
			)
		)
		(property "Description" ""
			(at 260.35 87.63 0)
			(effects
				(font
					(size 1.27 1.27)
				)
			)
		)
		(property "MPN" "EXB-28V101JX"
			(at 287.02 102.87 0)
			(effects
				(font
					(size 1.27 1.27)
					(thickness 0.15)
				)
				(justify left bottom)
				(hide yes)
			)
		)
		(property "Manufacturer" "Panasonic"
			(at 287.02 105.41 0)
			(effects
				(font
					(size 1.27 1.27)
					(thickness 0.15)
				)
				(justify left bottom)
				(hide yes)
			)
		)
		(property "Author" "Antmicro"
			(at 287.02 107.95 0)
			(effects
				(font
					(size 1.27 1.27)
					(thickness 0.15)
				)
				(justify left bottom)
				(hide yes)
			)
		)
		(property "License" "Apache-2.0"
			(at 287.02 110.49 0)
			(effects
				(font
					(size 1.27 1.27)
					(thickness 0.15)
				)
				(justify left bottom)
				(hide yes)
			)
		)
		(property "Val" "R_4x100R_0402"
			(at 274.32 85.09 0)
			(effects
				(font
					(size 1.27 1.27)
				)
			)
		)
		(pin "1"
		)
		(pin "2"
		)
		(pin "3"
		)
		(pin "4"
		)
		(pin "5"
		)
		(pin "6"
		)
		(pin "7"
		)
		(pin "8"
		)
		(instances
			(project ""
				(path ""
					(reference "R75")
					(unit 1)
				)
				(path ""
					(reference "R21")
					(unit 1)
				)
			)
		)
	)
	(symbol
		(lib_id "antmicroResistors0402:R_100R_0402")
		(at 181.61 146.05 0)
		(unit 1)
		(exclude_from_sim no)
		(in_bom yes)
		(on_board yes)
		(dnp no)
		(property "Reference" "R11"
			(at 186.69 144.78 0)
			(effects
				(font
					(size 1.27 1.27)
					(thickness 0.15)
				)
				(justify left)
			)
		)
		(property "Value" "R_100R_0402"
			(at 201.93 158.75 0)
			(effects
				(font
					(size 1.27 1.27)
					(thickness 0.15)
				)
				(justify left bottom)
				(hide yes)
			)
		)
		(property "Footprint" "antmicro-footprints:R_0402_1005Metric"
			(at 201.93 161.29 0)
			(effects
				(font
					(size 1.27 1.27)
					(thickness 0.15)
				)
				(justify left bottom)
				(hide yes)
			)
		)
		(property "Datasheet" "https://www.bourns.com/docs/product-datasheets/cr.pdf"
			(at 201.93 163.83 0)
			(effects
				(font
					(size 1.27 1.27)
					(thickness 0.15)
				)
				(justify left bottom)
				(hide yes)
			)
		)
		(property "Description" ""
			(at 181.61 146.05 0)
			(effects
				(font
					(size 1.27 1.27)
				)
			)
		)
		(property "MPN" "CR0402-FX-1000GLF"
			(at 201.93 166.37 0)
			(effects
				(font
					(size 1.27 1.27)
					(thickness 0.15)
				)
				(justify left bottom)
				(hide yes)
			)
		)
		(property "Manufacturer" "Bourns"
			(at 201.93 168.91 0)
			(effects
				(font
					(size 1.27 1.27)
					(thickness 0.15)
				)
				(justify left bottom)
				(hide yes)
			)
		)
		(property "License" "Apache-2.0"
			(at 201.93 171.45 0)
			(effects
				(font
					(size 1.27 1.27)
					(thickness 0.15)
				)
				(justify left bottom)
				(hide yes)
			)
		)
		(property "Author" "Antmicro"
			(at 201.93 173.99 0)
			(effects
				(font
					(size 1.27 1.27)
					(thickness 0.15)
				)
				(justify left bottom)
				(hide yes)
			)
		)
		(property "Val" "100R"
			(at 179.07 144.78 0)
			(effects
				(font
					(size 1.27 1.27)
					(thickness 0.15)
				)
			)
		)
		(property "Tolerance" "1%"
			(at 201.93 156.21 0)
			(effects
				(font
					(size 1.27 1.27)
				)
				(justify left bottom)
				(hide yes)
			)
		)
		(pin "1"
		)
		(pin "2"
		)
		(instances
			(project ""
				(path ""
					(reference "R64")
					(unit 1)
				)
				(path ""
					(reference "R11")
					(unit 1)
				)
			)
		)
	)
	(symbol
		(lib_id "antmicroResistorNetworksArrays:R_4x100R_0402_array")
		(at 179.07 129.54 0)
		(unit 1)
		(exclude_from_sim no)
		(in_bom yes)
		(on_board yes)
		(dnp no)
		(property "Reference" "R10"
			(at 181.61 127 0)
			(effects
				(font
					(size 1.27 1.27)
					(thickness 0.15)
				)
			)
		)
		(property "Value" "R_4x100R_0402_array"
			(at 205.74 134.62 0)
			(effects
				(font
					(size 1.27 1.27)
					(thickness 0.15)
				)
				(justify left bottom)
				(hide yes)
			)
		)
		(property "Footprint" "antmicro-footprints:R_Array_4x0402_Panasonic_EXB28V"
			(at 205.74 139.7 0)
			(effects
				(font
					(size 1.27 1.27)
					(thickness 0.15)
				)
				(justify left bottom)
				(hide yes)
			)
		)
		(property "Datasheet" "http://industrial.panasonic.com/cdbs/www-data/pdf/AOC0000/AOC0000C14.pdf"
			(at 205.74 142.24 0)
			(effects
				(font
					(size 1.27 1.27)
					(thickness 0.15)
				)
				(justify left bottom)
				(hide yes)
			)
		)
		(property "Description" ""
			(at 179.07 129.54 0)
			(effects
				(font
					(size 1.27 1.27)
				)
			)
		)
		(property "MPN" "EXB-28V101JX"
			(at 205.74 144.78 0)
			(effects
				(font
					(size 1.27 1.27)
					(thickness 0.15)
				)
				(justify left bottom)
				(hide yes)
			)
		)
		(property "Manufacturer" "Panasonic"
			(at 205.74 147.32 0)
			(effects
				(font
					(size 1.27 1.27)
					(thickness 0.15)
				)
				(justify left bottom)
				(hide yes)
			)
		)
		(property "Author" "Antmicro"
			(at 205.74 149.86 0)
			(effects
				(font
					(size 1.27 1.27)
					(thickness 0.15)
				)
				(justify left bottom)
				(hide yes)
			)
		)
		(property "License" "Apache-2.0"
			(at 205.74 152.4 0)
			(effects
				(font
					(size 1.27 1.27)
					(thickness 0.15)
				)
				(justify left bottom)
				(hide yes)
			)
		)
		(property "Val" "R_4x100R_0402"
			(at 193.04 127 0)
			(effects
				(font
					(size 1.27 1.27)
				)
			)
		)
		(pin "1"
		)
		(pin "2"
		)
		(pin "3"
		)
		(pin "4"
		)
		(pin "5"
		)
		(pin "6"
		)
		(pin "7"
		)
		(pin "8"
		)
		(instances
			(project ""
				(path ""
					(reference "R63")
					(unit 1)
				)
				(path ""
					(reference "R10")
					(unit 1)
				)
			)
		)
	)
	(symbol
		(lib_id "antmicropower:GND")
		(at 279.4 178.435 0)
		(unit 1)
		(exclude_from_sim no)
		(in_bom yes)
		(on_board yes)
		(dnp no)
		(property "Reference" "#PWR0103"
			(at 288.29 180.975 0)
			(effects
				(font
					(size 1.27 1.27)
					(thickness 0.15)
				)
				(justify left bottom)
				(hide yes)
			)
		)
		(property "Value" "GND"
			(at 279.4 182.245 0)
			(effects
				(font
					(size 1.27 1.27)
					(thickness 0.15)
				)
			)
		)
		(property "Footprint" ""
			(at 288.29 186.055 0)
			(effects
				(font
					(size 1.27 1.27)
					(thickness 0.15)
				)
				(justify left bottom)
				(hide yes)
			)
		)
		(property "Datasheet" ""
			(at 288.29 191.135 0)
			(effects
				(font
					(size 1.27 1.27)
					(thickness 0.15)
				)
				(justify left bottom)
				(hide yes)
			)
		)
		(property "Description" ""
			(at 279.4 178.435 0)
			(effects
				(font
					(size 1.27 1.27)
				)
			)
		)
		(property "Author" "Antmicro"
			(at 288.29 186.055 0)
			(effects
				(font
					(size 1.27 1.27)
					(thickness 0.15)
				)
				(justify left bottom)
				(hide yes)
			)
		)
		(property "License" "Apache-2.0"
			(at 288.29 188.595 0)
			(effects
				(font
					(size 1.27 1.27)
					(thickness 0.15)
				)
				(justify left bottom)
				(hide yes)
			)
		)
		(pin "1"
		)
		(instances
			(project ""
				(path ""
					(reference "#PWR0106")
					(unit 1)
				)
				(path ""
					(reference "#PWR0103")
					(unit 1)
				)
			)
		)
	)
	(symbol
		(lib_id "antmicroResistorNetworksArrays:R_4x100R_0402_array")
		(at 179.07 101.6 0)
		(unit 1)
		(exclude_from_sim no)
		(in_bom yes)
		(on_board yes)
		(dnp no)
		(property "Reference" "R8"
			(at 181.61 99.06 0)
			(effects
				(font
					(size 1.27 1.27)
					(thickness 0.15)
				)
			)
		)
		(property "Value" "R_4x100R_0402_array"
			(at 205.74 106.68 0)
			(effects
				(font
					(size 1.27 1.27)
					(thickness 0.15)
				)
				(justify left bottom)
				(hide yes)
			)
		)
		(property "Footprint" "antmicro-footprints:R_Array_4x0402_Panasonic_EXB28V"
			(at 205.74 111.76 0)
			(effects
				(font
					(size 1.27 1.27)
					(thickness 0.15)
				)
				(justify left bottom)
				(hide yes)
			)
		)
		(property "Datasheet" "http://industrial.panasonic.com/cdbs/www-data/pdf/AOC0000/AOC0000C14.pdf"
			(at 205.74 114.3 0)
			(effects
				(font
					(size 1.27 1.27)
					(thickness 0.15)
				)
				(justify left bottom)
				(hide yes)
			)
		)
		(property "Description" ""
			(at 179.07 101.6 0)
			(effects
				(font
					(size 1.27 1.27)
				)
			)
		)
		(property "MPN" "EXB-28V101JX"
			(at 205.74 116.84 0)
			(effects
				(font
					(size 1.27 1.27)
					(thickness 0.15)
				)
				(justify left bottom)
				(hide yes)
			)
		)
		(property "Manufacturer" "Panasonic"
			(at 205.74 119.38 0)
			(effects
				(font
					(size 1.27 1.27)
					(thickness 0.15)
				)
				(justify left bottom)
				(hide yes)
			)
		)
		(property "Author" "Antmicro"
			(at 205.74 121.92 0)
			(effects
				(font
					(size 1.27 1.27)
					(thickness 0.15)
				)
				(justify left bottom)
				(hide yes)
			)
		)
		(property "License" "Apache-2.0"
			(at 205.74 124.46 0)
			(effects
				(font
					(size 1.27 1.27)
					(thickness 0.15)
				)
				(justify left bottom)
				(hide yes)
			)
		)
		(property "Val" "R_4x100R_0402"
			(at 193.04 99.06 0)
			(effects
				(font
					(size 1.27 1.27)
				)
			)
		)
		(pin "1"
		)
		(pin "2"
		)
		(pin "3"
		)
		(pin "4"
		)
		(pin "5"
		)
		(pin "6"
		)
		(pin "7"
		)
		(pin "8"
		)
		(instances
			(project ""
				(path ""
					(reference "R61")
					(unit 1)
				)
				(path ""
					(reference "R8")
					(unit 1)
				)
			)
		)
	)
	(symbol
		(lib_id "antmicroResistorNetworksArrays:R_4x100R_0402_array")
		(at 179.07 115.57 0)
		(unit 1)
		(exclude_from_sim no)
		(in_bom yes)
		(on_board yes)
		(dnp no)
		(property "Reference" "R9"
			(at 181.61 113.03 0)
			(effects
				(font
					(size 1.27 1.27)
					(thickness 0.15)
				)
			)
		)
		(property "Value" "R_4x100R_0402_array"
			(at 205.74 120.65 0)
			(effects
				(font
					(size 1.27 1.27)
					(thickness 0.15)
				)
				(justify left bottom)
				(hide yes)
			)
		)
		(property "Footprint" "antmicro-footprints:R_Array_4x0402_Panasonic_EXB28V"
			(at 205.74 125.73 0)
			(effects
				(font
					(size 1.27 1.27)
					(thickness 0.15)
				)
				(justify left bottom)
				(hide yes)
			)
		)
		(property "Datasheet" "http://industrial.panasonic.com/cdbs/www-data/pdf/AOC0000/AOC0000C14.pdf"
			(at 205.74 128.27 0)
			(effects
				(font
					(size 1.27 1.27)
					(thickness 0.15)
				)
				(justify left bottom)
				(hide yes)
			)
		)
		(property "Description" ""
			(at 179.07 115.57 0)
			(effects
				(font
					(size 1.27 1.27)
				)
			)
		)
		(property "MPN" "EXB-28V101JX"
			(at 205.74 130.81 0)
			(effects
				(font
					(size 1.27 1.27)
					(thickness 0.15)
				)
				(justify left bottom)
				(hide yes)
			)
		)
		(property "Manufacturer" "Panasonic"
			(at 205.74 133.35 0)
			(effects
				(font
					(size 1.27 1.27)
					(thickness 0.15)
				)
				(justify left bottom)
				(hide yes)
			)
		)
		(property "Author" "Antmicro"
			(at 205.74 135.89 0)
			(effects
				(font
					(size 1.27 1.27)
					(thickness 0.15)
				)
				(justify left bottom)
				(hide yes)
			)
		)
		(property "License" "Apache-2.0"
			(at 205.74 138.43 0)
			(effects
				(font
					(size 1.27 1.27)
					(thickness 0.15)
				)
				(justify left bottom)
				(hide yes)
			)
		)
		(property "Val" "R_4x100R_0402"
			(at 193.04 113.03 0)
			(effects
				(font
					(size 1.27 1.27)
				)
			)
		)
		(pin "1"
		)
		(pin "2"
		)
		(pin "3"
		)
		(pin "4"
		)
		(pin "5"
		)
		(pin "6"
		)
		(pin "7"
		)
		(pin "8"
		)
		(instances
			(project ""
				(path ""
					(reference "R62")
					(unit 1)
				)
				(path ""
					(reference "R9")
					(unit 1)
				)
			)
		)
	)
	(symbol
		(lib_id "antmicroResistorNetworksArrays:R_4x100R_0402_array")
		(at 179.07 87.63 0)
		(unit 1)
		(exclude_from_sim no)
		(in_bom yes)
		(on_board yes)
		(dnp no)
		(property "Reference" "R7"
			(at 181.61 85.09 0)
			(effects
				(font
					(size 1.27 1.27)
					(thickness 0.15)
				)
			)
		)
		(property "Value" "R_4x100R_0402_array"
			(at 205.74 92.71 0)
			(effects
				(font
					(size 1.27 1.27)
					(thickness 0.15)
				)
				(justify left bottom)
				(hide yes)
			)
		)
		(property "Footprint" "antmicro-footprints:R_Array_4x0402_Panasonic_EXB28V"
			(at 205.74 97.79 0)
			(effects
				(font
					(size 1.27 1.27)
					(thickness 0.15)
				)
				(justify left bottom)
				(hide yes)
			)
		)
		(property "Datasheet" "http://industrial.panasonic.com/cdbs/www-data/pdf/AOC0000/AOC0000C14.pdf"
			(at 205.74 100.33 0)
			(effects
				(font
					(size 1.27 1.27)
					(thickness 0.15)
				)
				(justify left bottom)
				(hide yes)
			)
		)
		(property "Description" ""
			(at 179.07 87.63 0)
			(effects
				(font
					(size 1.27 1.27)
				)
			)
		)
		(property "MPN" "EXB-28V101JX"
			(at 205.74 102.87 0)
			(effects
				(font
					(size 1.27 1.27)
					(thickness 0.15)
				)
				(justify left bottom)
				(hide yes)
			)
		)
		(property "Manufacturer" "Panasonic"
			(at 205.74 105.41 0)
			(effects
				(font
					(size 1.27 1.27)
					(thickness 0.15)
				)
				(justify left bottom)
				(hide yes)
			)
		)
		(property "Author" "Antmicro"
			(at 205.74 107.95 0)
			(effects
				(font
					(size 1.27 1.27)
					(thickness 0.15)
				)
				(justify left bottom)
				(hide yes)
			)
		)
		(property "License" "Apache-2.0"
			(at 205.74 110.49 0)
			(effects
				(font
					(size 1.27 1.27)
					(thickness 0.15)
				)
				(justify left bottom)
				(hide yes)
			)
		)
		(property "Val" "R_4x100R_0402"
			(at 193.04 85.09 0)
			(effects
				(font
					(size 1.27 1.27)
				)
			)
		)
		(pin "1"
		)
		(pin "2"
		)
		(pin "3"
		)
		(pin "4"
		)
		(pin "5"
		)
		(pin "6"
		)
		(pin "7"
		)
		(pin "8"
		)
		(instances
			(project ""
				(path ""
					(reference "R60")
					(unit 1)
				)
				(path ""
					(reference "R7")
					(unit 1)
				)
			)
		)
	)
	(symbol
		(lib_id "antmicroResistors0402:R_100R_0402")
		(at 262.89 173.99 0)
		(unit 1)
		(exclude_from_sim no)
		(in_bom yes)
		(on_board yes)
		(dnp no)
		(property "Reference" "R54"
			(at 267.97 172.72 0)
			(effects
				(font
					(size 1.27 1.27)
					(thickness 0.15)
				)
				(justify left)
			)
		)
		(property "Value" "R_100R_0402"
			(at 283.21 186.69 0)
			(effects
				(font
					(size 1.27 1.27)
					(thickness 0.15)
				)
				(justify left bottom)
				(hide yes)
			)
		)
		(property "Footprint" "antmicro-footprints:R_0402_1005Metric"
			(at 283.21 189.23 0)
			(effects
				(font
					(size 1.27 1.27)
					(thickness 0.15)
				)
				(justify left bottom)
				(hide yes)
			)
		)
		(property "Datasheet" "https://www.bourns.com/docs/product-datasheets/cr.pdf"
			(at 283.21 191.77 0)
			(effects
				(font
					(size 1.27 1.27)
					(thickness 0.15)
				)
				(justify left bottom)
				(hide yes)
			)
		)
		(property "Description" ""
			(at 262.89 173.99 0)
			(effects
				(font
					(size 1.27 1.27)
				)
			)
		)
		(property "MPN" "CR0402-FX-1000GLF"
			(at 283.21 194.31 0)
			(effects
				(font
					(size 1.27 1.27)
					(thickness 0.15)
				)
				(justify left bottom)
				(hide yes)
			)
		)
		(property "Manufacturer" "Bourns"
			(at 283.21 196.85 0)
			(effects
				(font
					(size 1.27 1.27)
					(thickness 0.15)
				)
				(justify left bottom)
				(hide yes)
			)
		)
		(property "License" "Apache-2.0"
			(at 283.21 199.39 0)
			(effects
				(font
					(size 1.27 1.27)
					(thickness 0.15)
				)
				(justify left bottom)
				(hide yes)
			)
		)
		(property "Author" "Antmicro"
			(at 283.21 201.93 0)
			(effects
				(font
					(size 1.27 1.27)
					(thickness 0.15)
				)
				(justify left bottom)
				(hide yes)
			)
		)
		(property "Val" "100R"
			(at 260.35 172.72 0)
			(effects
				(font
					(size 1.27 1.27)
					(thickness 0.15)
				)
			)
		)
		(property "Tolerance" "1%"
			(at 283.21 184.15 0)
			(effects
				(font
					(size 1.27 1.27)
				)
				(justify left bottom)
				(hide yes)
			)
		)
		(pin "1"
		)
		(pin "2"
		)
		(instances
			(project ""
				(path ""
					(reference "R83")
					(unit 1)
				)
				(path ""
					(reference "R54")
					(unit 1)
				)
			)
		)
	)
	(symbol
		(lib_id "antmicroResistors0402:R_100R_0402")
		(at 181.61 78.74 0)
		(unit 1)
		(exclude_from_sim no)
		(in_bom yes)
		(on_board yes)
		(dnp no)
		(property "Reference" "R59"
			(at 186.69 77.47 0)
			(effects
				(font
					(size 1.27 1.27)
					(thickness 0.15)
				)
				(justify left)
			)
		)
		(property "Value" "R_100R_0402"
			(at 201.93 91.44 0)
			(effects
				(font
					(size 1.27 1.27)
					(thickness 0.15)
				)
				(justify left bottom)
				(hide yes)
			)
		)
		(property "Footprint" "antmicro-footprints:R_0402_1005Metric"
			(at 201.93 93.98 0)
			(effects
				(font
					(size 1.27 1.27)
					(thickness 0.15)
				)
				(justify left bottom)
				(hide yes)
			)
		)
		(property "Datasheet" "https://www.bourns.com/docs/product-datasheets/cr.pdf"
			(at 201.93 96.52 0)
			(effects
				(font
					(size 1.27 1.27)
					(thickness 0.15)
				)
				(justify left bottom)
				(hide yes)
			)
		)
		(property "Description" ""
			(at 181.61 78.74 0)
			(effects
				(font
					(size 1.27 1.27)
				)
			)
		)
		(property "MPN" "CR0402-FX-1000GLF"
			(at 201.93 99.06 0)
			(effects
				(font
					(size 1.27 1.27)
					(thickness 0.15)
				)
				(justify left bottom)
				(hide yes)
			)
		)
		(property "Manufacturer" "Bourns"
			(at 201.93 101.6 0)
			(effects
				(font
					(size 1.27 1.27)
					(thickness 0.15)
				)
				(justify left bottom)
				(hide yes)
			)
		)
		(property "License" "Apache-2.0"
			(at 201.93 104.14 0)
			(effects
				(font
					(size 1.27 1.27)
					(thickness 0.15)
				)
				(justify left bottom)
				(hide yes)
			)
		)
		(property "Author" "Antmicro"
			(at 201.93 106.68 0)
			(effects
				(font
					(size 1.27 1.27)
					(thickness 0.15)
				)
				(justify left bottom)
				(hide yes)
			)
		)
		(property "Val" "100R"
			(at 179.07 77.47 0)
			(effects
				(font
					(size 1.27 1.27)
					(thickness 0.15)
				)
			)
		)
		(property "Tolerance" "1%"
			(at 201.93 88.9 0)
			(effects
				(font
					(size 1.27 1.27)
				)
				(justify left bottom)
				(hide yes)
			)
		)
		(pin "1"
		)
		(pin "2"
		)
		(instances
			(project ""
				(path ""
					(reference "R89")
					(unit 1)
				)
				(path ""
					(reference "R59")
					(unit 1)
				)
			)
		)
	)
	(symbol
		(lib_id "antmicroResistorNetworksArrays:R_4x100R_0402_array")
		(at 179.07 59.69 0)
		(unit 1)
		(exclude_from_sim no)
		(in_bom yes)
		(on_board yes)
		(dnp no)
		(property "Reference" "R5"
			(at 181.61 57.15 0)
			(effects
				(font
					(size 1.27 1.27)
					(thickness 0.15)
				)
			)
		)
		(property "Value" "R_4x100R_0402_array"
			(at 205.74 64.77 0)
			(effects
				(font
					(size 1.27 1.27)
					(thickness 0.15)
				)
				(justify left bottom)
				(hide yes)
			)
		)
		(property "Footprint" "antmicro-footprints:R_Array_4x0402_Panasonic_EXB28V"
			(at 205.74 69.85 0)
			(effects
				(font
					(size 1.27 1.27)
					(thickness 0.15)
				)
				(justify left bottom)
				(hide yes)
			)
		)
		(property "Datasheet" "http://industrial.panasonic.com/cdbs/www-data/pdf/AOC0000/AOC0000C14.pdf"
			(at 205.74 72.39 0)
			(effects
				(font
					(size 1.27 1.27)
					(thickness 0.15)
				)
				(justify left bottom)
				(hide yes)
			)
		)
		(property "Description" ""
			(at 179.07 59.69 0)
			(effects
				(font
					(size 1.27 1.27)
				)
			)
		)
		(property "MPN" "EXB-28V101JX"
			(at 205.74 74.93 0)
			(effects
				(font
					(size 1.27 1.27)
					(thickness 0.15)
				)
				(justify left bottom)
				(hide yes)
			)
		)
		(property "Manufacturer" "Panasonic"
			(at 205.74 77.47 0)
			(effects
				(font
					(size 1.27 1.27)
					(thickness 0.15)
				)
				(justify left bottom)
				(hide yes)
			)
		)
		(property "Author" "Antmicro"
			(at 205.74 80.01 0)
			(effects
				(font
					(size 1.27 1.27)
					(thickness 0.15)
				)
				(justify left bottom)
				(hide yes)
			)
		)
		(property "License" "Apache-2.0"
			(at 205.74 82.55 0)
			(effects
				(font
					(size 1.27 1.27)
					(thickness 0.15)
				)
				(justify left bottom)
				(hide yes)
			)
		)
		(property "Val" "R_4x100R_0402"
			(at 193.04 57.15 0)
			(effects
				(font
					(size 1.27 1.27)
				)
			)
		)
		(pin "1"
		)
		(pin "2"
		)
		(pin "3"
		)
		(pin "4"
		)
		(pin "5"
		)
		(pin "6"
		)
		(pin "7"
		)
		(pin "8"
		)
		(instances
			(project ""
				(path ""
					(reference "R58")
					(unit 1)
				)
				(path ""
					(reference "R5")
					(unit 1)
				)
			)
		)
	)
	(symbol
		(lib_id "antmicroResistors0402:R_100R_0402")
		(at 181.61 76.2 0)
		(unit 1)
		(exclude_from_sim no)
		(in_bom yes)
		(on_board yes)
		(dnp no)
		(property "Reference" "R20"
			(at 186.69 74.93 0)
			(effects
				(font
					(size 1.27 1.27)
					(thickness 0.15)
				)
				(justify left)
			)
		)
		(property "Value" "R_100R_0402"
			(at 201.93 88.9 0)
			(effects
				(font
					(size 1.27 1.27)
					(thickness 0.15)
				)
				(justify left bottom)
				(hide yes)
			)
		)
		(property "Footprint" "antmicro-footprints:R_0402_1005Metric"
			(at 201.93 91.44 0)
			(effects
				(font
					(size 1.27 1.27)
					(thickness 0.15)
				)
				(justify left bottom)
				(hide yes)
			)
		)
		(property "Datasheet" "https://www.bourns.com/docs/product-datasheets/cr.pdf"
			(at 201.93 93.98 0)
			(effects
				(font
					(size 1.27 1.27)
					(thickness 0.15)
				)
				(justify left bottom)
				(hide yes)
			)
		)
		(property "Description" ""
			(at 181.61 76.2 0)
			(effects
				(font
					(size 1.27 1.27)
				)
			)
		)
		(property "MPN" "CR0402-FX-1000GLF"
			(at 201.93 96.52 0)
			(effects
				(font
					(size 1.27 1.27)
					(thickness 0.15)
				)
				(justify left bottom)
				(hide yes)
			)
		)
		(property "Manufacturer" "Bourns"
			(at 201.93 99.06 0)
			(effects
				(font
					(size 1.27 1.27)
					(thickness 0.15)
				)
				(justify left bottom)
				(hide yes)
			)
		)
		(property "License" "Apache-2.0"
			(at 201.93 101.6 0)
			(effects
				(font
					(size 1.27 1.27)
					(thickness 0.15)
				)
				(justify left bottom)
				(hide yes)
			)
		)
		(property "Author" "Antmicro"
			(at 201.93 104.14 0)
			(effects
				(font
					(size 1.27 1.27)
					(thickness 0.15)
				)
				(justify left bottom)
				(hide yes)
			)
		)
		(property "Val" "100R"
			(at 179.07 74.93 0)
			(effects
				(font
					(size 1.27 1.27)
					(thickness 0.15)
				)
			)
		)
		(property "Tolerance" "1%"
			(at 201.93 86.36 0)
			(effects
				(font
					(size 1.27 1.27)
				)
				(justify left bottom)
				(hide yes)
			)
		)
		(pin "1"
		)
		(pin "2"
		)
		(instances
			(project ""
				(path ""
					(reference "R88")
					(unit 1)
				)
				(path ""
					(reference "R20")
					(unit 1)
				)
			)
		)
	)
	(symbol
		(lib_id "antmicroResistorNetworksArrays:R_4x100R_0402_array")
		(at 260.35 101.6 0)
		(unit 1)
		(exclude_from_sim no)
		(in_bom yes)
		(on_board yes)
		(dnp no)
		(property "Reference" "R22"
			(at 262.89 99.06 0)
			(effects
				(font
					(size 1.27 1.27)
					(thickness 0.15)
				)
			)
		)
		(property "Value" "R_4x100R_0402_array"
			(at 287.02 106.68 0)
			(effects
				(font
					(size 1.27 1.27)
					(thickness 0.15)
				)
				(justify left bottom)
				(hide yes)
			)
		)
		(property "Footprint" "antmicro-footprints:R_Array_4x0402_Panasonic_EXB28V"
			(at 287.02 111.76 0)
			(effects
				(font
					(size 1.27 1.27)
					(thickness 0.15)
				)
				(justify left bottom)
				(hide yes)
			)
		)
		(property "Datasheet" "http://industrial.panasonic.com/cdbs/www-data/pdf/AOC0000/AOC0000C14.pdf"
			(at 287.02 114.3 0)
			(effects
				(font
					(size 1.27 1.27)
					(thickness 0.15)
				)
				(justify left bottom)
				(hide yes)
			)
		)
		(property "Description" ""
			(at 260.35 101.6 0)
			(effects
				(font
					(size 1.27 1.27)
				)
			)
		)
		(property "MPN" "EXB-28V101JX"
			(at 287.02 116.84 0)
			(effects
				(font
					(size 1.27 1.27)
					(thickness 0.15)
				)
				(justify left bottom)
				(hide yes)
			)
		)
		(property "Manufacturer" "Panasonic"
			(at 287.02 119.38 0)
			(effects
				(font
					(size 1.27 1.27)
					(thickness 0.15)
				)
				(justify left bottom)
				(hide yes)
			)
		)
		(property "Author" "Antmicro"
			(at 287.02 121.92 0)
			(effects
				(font
					(size 1.27 1.27)
					(thickness 0.15)
				)
				(justify left bottom)
				(hide yes)
			)
		)
		(property "License" "Apache-2.0"
			(at 287.02 124.46 0)
			(effects
				(font
					(size 1.27 1.27)
					(thickness 0.15)
				)
				(justify left bottom)
				(hide yes)
			)
		)
		(property "Val" "R_4x100R_0402"
			(at 274.32 99.06 0)
			(effects
				(font
					(size 1.27 1.27)
				)
			)
		)
		(pin "1"
		)
		(pin "2"
		)
		(pin "3"
		)
		(pin "4"
		)
		(pin "5"
		)
		(pin "6"
		)
		(pin "7"
		)
		(pin "8"
		)
		(instances
			(project ""
				(path ""
					(reference "R76")
					(unit 1)
				)
				(path ""
					(reference "R22")
					(unit 1)
				)
			)
		)
	)
	(symbol
		(lib_id "antmicroResistorNetworksArrays:R_4x100R_0402_array")
		(at 179.07 45.72 0)
		(unit 1)
		(exclude_from_sim no)
		(in_bom yes)
		(on_board yes)
		(dnp no)
		(property "Reference" "R4"
			(at 181.61 43.18 0)
			(effects
				(font
					(size 1.27 1.27)
					(thickness 0.15)
				)
			)
		)
		(property "Value" "R_4x100R_0402_array"
			(at 205.74 50.8 0)
			(effects
				(font
					(size 1.27 1.27)
					(thickness 0.15)
				)
				(justify left bottom)
				(hide yes)
			)
		)
		(property "Footprint" "antmicro-footprints:R_Array_4x0402_Panasonic_EXB28V"
			(at 205.74 55.88 0)
			(effects
				(font
					(size 1.27 1.27)
					(thickness 0.15)
				)
				(justify left bottom)
				(hide yes)
			)
		)
		(property "Datasheet" "http://industrial.panasonic.com/cdbs/www-data/pdf/AOC0000/AOC0000C14.pdf"
			(at 205.74 58.42 0)
			(effects
				(font
					(size 1.27 1.27)
					(thickness 0.15)
				)
				(justify left bottom)
				(hide yes)
			)
		)
		(property "Description" ""
			(at 179.07 45.72 0)
			(effects
				(font
					(size 1.27 1.27)
				)
			)
		)
		(property "MPN" "EXB-28V101JX"
			(at 205.74 60.96 0)
			(effects
				(font
					(size 1.27 1.27)
					(thickness 0.15)
				)
				(justify left bottom)
				(hide yes)
			)
		)
		(property "Manufacturer" "Panasonic"
			(at 205.74 63.5 0)
			(effects
				(font
					(size 1.27 1.27)
					(thickness 0.15)
				)
				(justify left bottom)
				(hide yes)
			)
		)
		(property "Author" "Antmicro"
			(at 205.74 66.04 0)
			(effects
				(font
					(size 1.27 1.27)
					(thickness 0.15)
				)
				(justify left bottom)
				(hide yes)
			)
		)
		(property "License" "Apache-2.0"
			(at 205.74 68.58 0)
			(effects
				(font
					(size 1.27 1.27)
					(thickness 0.15)
				)
				(justify left bottom)
				(hide yes)
			)
		)
		(property "Val" "R_4x100R_0402"
			(at 193.04 43.18 0)
			(effects
				(font
					(size 1.27 1.27)
				)
			)
		)
		(pin "1"
		)
		(pin "2"
		)
		(pin "3"
		)
		(pin "4"
		)
		(pin "5"
		)
		(pin "6"
		)
		(pin "7"
		)
		(pin "8"
		)
		(instances
			(project ""
				(path ""
					(reference "R57")
					(unit 1)
				)
				(path ""
					(reference "R4")
					(unit 1)
				)
			)
		)
	)
	(symbol
		(lib_id "antmicroResistorNetworksArrays:R_4x100R_0402_array")
		(at 260.35 59.69 0)
		(unit 1)
		(exclude_from_sim no)
		(in_bom yes)
		(on_board yes)
		(dnp no)
		(property "Reference" "R19"
			(at 262.89 57.15 0)
			(effects
				(font
					(size 1.27 1.27)
					(thickness 0.15)
				)
			)
		)
		(property "Value" "R_4x100R_0402_array"
			(at 287.02 64.77 0)
			(effects
				(font
					(size 1.27 1.27)
					(thickness 0.15)
				)
				(justify left bottom)
				(hide yes)
			)
		)
		(property "Footprint" "antmicro-footprints:R_Array_4x0402_Panasonic_EXB28V"
			(at 287.02 69.85 0)
			(effects
				(font
					(size 1.27 1.27)
					(thickness 0.15)
				)
				(justify left bottom)
				(hide yes)
			)
		)
		(property "Datasheet" "http://industrial.panasonic.com/cdbs/www-data/pdf/AOC0000/AOC0000C14.pdf"
			(at 287.02 72.39 0)
			(effects
				(font
					(size 1.27 1.27)
					(thickness 0.15)
				)
				(justify left bottom)
				(hide yes)
			)
		)
		(property "Description" ""
			(at 260.35 59.69 0)
			(effects
				(font
					(size 1.27 1.27)
				)
			)
		)
		(property "MPN" "EXB-28V101JX"
			(at 287.02 74.93 0)
			(effects
				(font
					(size 1.27 1.27)
					(thickness 0.15)
				)
				(justify left bottom)
				(hide yes)
			)
		)
		(property "Manufacturer" "Panasonic"
			(at 287.02 77.47 0)
			(effects
				(font
					(size 1.27 1.27)
					(thickness 0.15)
				)
				(justify left bottom)
				(hide yes)
			)
		)
		(property "Author" "Antmicro"
			(at 287.02 80.01 0)
			(effects
				(font
					(size 1.27 1.27)
					(thickness 0.15)
				)
				(justify left bottom)
				(hide yes)
			)
		)
		(property "License" "Apache-2.0"
			(at 287.02 82.55 0)
			(effects
				(font
					(size 1.27 1.27)
					(thickness 0.15)
				)
				(justify left bottom)
				(hide yes)
			)
		)
		(property "Val" "R_4x100R_0402"
			(at 274.32 57.15 0)
			(effects
				(font
					(size 1.27 1.27)
				)
			)
		)
		(pin "1"
		)
		(pin "2"
		)
		(pin "3"
		)
		(pin "4"
		)
		(pin "5"
		)
		(pin "6"
		)
		(pin "7"
		)
		(pin "8"
		)
		(instances
			(project ""
				(path ""
					(reference "R73")
					(unit 1)
				)
				(path ""
					(reference "R19")
					(unit 1)
				)
			)
		)
	)
	(symbol
		(lib_id "antmicroResistors0402:R_100R_0402")
		(at 262.89 76.2 0)
		(unit 1)
		(exclude_from_sim no)
		(in_bom yes)
		(on_board yes)
		(dnp no)
		(property "Reference" "R85"
			(at 267.97 74.93 0)
			(effects
				(font
					(size 1.27 1.27)
					(thickness 0.15)
				)
				(justify left)
			)
		)
		(property "Value" "R_100R_0402"
			(at 283.21 88.9 0)
			(effects
				(font
					(size 1.27 1.27)
					(thickness 0.15)
				)
				(justify left bottom)
				(hide yes)
			)
		)
		(property "Footprint" "antmicro-footprints:R_0402_1005Metric"
			(at 283.21 91.44 0)
			(effects
				(font
					(size 1.27 1.27)
					(thickness 0.15)
				)
				(justify left bottom)
				(hide yes)
			)
		)
		(property "Datasheet" "https://www.bourns.com/docs/product-datasheets/cr.pdf"
			(at 283.21 93.98 0)
			(effects
				(font
					(size 1.27 1.27)
					(thickness 0.15)
				)
				(justify left bottom)
				(hide yes)
			)
		)
		(property "Description" ""
			(at 262.89 76.2 0)
			(effects
				(font
					(size 1.27 1.27)
				)
			)
		)
		(property "MPN" "CR0402-FX-1000GLF"
			(at 283.21 96.52 0)
			(effects
				(font
					(size 1.27 1.27)
					(thickness 0.15)
				)
				(justify left bottom)
				(hide yes)
			)
		)
		(property "Manufacturer" "Bourns"
			(at 283.21 99.06 0)
			(effects
				(font
					(size 1.27 1.27)
					(thickness 0.15)
				)
				(justify left bottom)
				(hide yes)
			)
		)
		(property "License" "Apache-2.0"
			(at 283.21 101.6 0)
			(effects
				(font
					(size 1.27 1.27)
					(thickness 0.15)
				)
				(justify left bottom)
				(hide yes)
			)
		)
		(property "Author" "Antmicro"
			(at 283.21 104.14 0)
			(effects
				(font
					(size 1.27 1.27)
					(thickness 0.15)
				)
				(justify left bottom)
				(hide yes)
			)
		)
		(property "Val" "100R"
			(at 260.35 74.93 0)
			(effects
				(font
					(size 1.27 1.27)
					(thickness 0.15)
				)
			)
		)
		(property "Tolerance" "1%"
			(at 283.21 86.36 0)
			(effects
				(font
					(size 1.27 1.27)
				)
				(justify left bottom)
				(hide yes)
			)
		)
		(pin "1"
		)
		(pin "2"
		)
		(instances
			(project ""
				(path ""
					(reference "R91")
					(unit 1)
				)
				(path ""
					(reference "R85")
					(unit 1)
				)
			)
		)
	)
)
